G04 ================== begin FILE IDENTIFICATION RECORD ==================*
G04 Layout Name:  9052_F0T_PDB_Converter_Brick_F_V03_1208_1600.brd*
G04 Film Name:    in2*
G04 File Format:  Gerber RS274X*
G04 File Origin:  Cadence Allegro 17.2-S081*
G04 Origin Date:  Wed Dec 21 09:54:58 2022*
G04 *
G04 Layer:  DRAWING FORMAT/TITLE_BLOCK_A*
G04 Layer:  PIN/SPECIAL_DRILL*
G04 Layer:  DRAWING FORMAT/TITLE_BLOCK*
G04 Layer:  VIA CLASS/IN2*
G04 Layer:  PIN/IN2*
G04 Layer:  MANUFACTURING/PHOTOPLOT_OUTLINE*
G04 Layer:  ETCH/IN2*
G04 Layer:  DRAWING FORMAT/TITLE_DATA_IN2*
G04 *
G04 Offset:    (0.00 0.00)*
G04 Mirror:    No*
G04 Mode:      Positive*
G04 Rotation:  0*
G04 FullContactRelief:  No*
G04 UndefLineWidth:     6.00*
G04 ================== end FILE IDENTIFICATION RECORD ====================*
%FSLAX25Y25*MOIN*%
%IR0*IPPOS*OFA0.00000B0.00000*MIA0B0*SFA1.00000B1.00000*%
%ADD10C,.02*%
%AMMACRO20*
4,1,41,-.40714,-.11826,
-.427771,-.11755,
-.447965,-.113268,
-.467108,-.105544,
-.48462,-.094614,
-.499967,-.080809,
-.512684,-.064548,
-.522385,-.046326,
-.528773,-.026697,
-.531656,-.006256,
-.530946,.014374,
-.526664,.034568,
-.518941,.053712,
-.50801,.071223,
-.494205,.086571,
-.477944,.099288,
-.459723,.108988,
-.440093,.115377,
-.419653,.11826,
-.40714,.11826,
.33517,.07906,
.45275,.07906,
.466479,.077859,
.47979,.074292,
.49228,.068468,
.503569,.060563,
.513313,.050819,
.521218,.03953,
.527042,.02704,
.530609,.013729,
.53181,0.0,
.530609,-.013729,
.527042,-.02704,
.521218,-.03953,
.513313,-.050819,
.503569,-.060563,
.49228,-.068468,
.47979,-.074292,
.466479,-.077859,
.45275,-.07906,
.33517,-.07906,
-.40714,-.11826,
0.0*
%
%ADD20MACRO20*%
%ADD12C,.05*%
%ADD15C,.06*%
%ADD14C,.062*%
%ADD13C,.018*%
%ADD22C,.066*%
%ADD18C,.06015*%
%ADD17C,.093*%
%ADD19C,.085*%
%ADD11C,.058*%
%ADD21C,.4*%
%ADD16C,.123*%
%ADD23C,.01*%
%ADD24C,.015*%
%ADD25C,.025*%
%ADD26C,.035*%
%ADD27C,.006*%
%ADD28C,.0051*%
%ADD41C,.03004*%
%ADD29C,.07004*%
%ADD43C,.07006*%
%ADD36C,.07204*%
%ADD39C,.07018*%
%ADD38C,.07604*%
%ADD30C,.11004*%
%ADD37C,.11204*%
%ADD34C,.10304*%
%ADD40C,.11018*%
%ADD31C,.13304*%
%ADD35C,.14304*%
%ADD33C,.30604*%
%ADD42C,.40406*%
%ADD32C,.16506*%
G75*
%LPD*%
G75*
G36*
G01X932000Y576740D02*
X1271654D01*
G02X1289339Y559055I0J-17685D01*
G01Y19685D01*
G02X1271654Y2000I-17685J0D01*
G01X19685D01*
G02X2000Y19685I0J17685D01*
G01Y63268D01*
G02X11811Y73079I9811J0D01*
G01X37796D01*
G03X41764Y77047I0J3969D01*
G01Y122323D01*
G03X37796Y126291I-3969J-1D01*
G01X11811D01*
G02X2000Y136102I0J9811D01*
G01Y445787D01*
G02X11811Y455598I9811J0D01*
G01X37795D01*
G03X41764Y459567I0J3969D01*
G01Y504843D01*
G03X37796Y508811I-3969J-1D01*
G01X11811D01*
G02X2000Y518622I0J9811D01*
G01Y559055D01*
G02X19685Y576740I17685J0D01*
G01X142000D01*
Y574742D01*
X19685D01*
G03X3998Y559055I0J-15687D01*
G01Y518622D01*
G03X11811Y510808I7814J0D01*
G01X37796D01*
G02X43761Y504843I0J-5966D01*
G01X43762D01*
Y459567D01*
G02X37795Y453600I-5967J0D01*
G01X11811D01*
G03X3998Y445787I0J-7813D01*
G01Y136102D01*
G03X11811Y128288I7814J0D01*
G01X37796D01*
G02X43761Y122323I-1J-5966D01*
G01X43762D01*
Y77047D01*
X43761D01*
G02X37796Y71082I-5966J1D01*
G01X11811D01*
G03X3998Y63270I0J-7813D01*
G01Y19685D01*
G03X19685Y3998I15687J0D01*
G01X1271654D01*
G03X1287341Y19685I0J15687D01*
G01Y559055D01*
G03X1271654Y574742I-15687J0D01*
G01X932000D01*
Y576740D01*
G37*
G36*
G01X69077Y457591D02*
X124545D01*
G02X124687Y457532I0J-200D01*
G01X134397D01*
G02X134539Y457473I0J-200D01*
G01X136140Y455872D01*
G02X136199Y455730I-141J-142D01*
G01Y329823D01*
G03X136258Y329681I200J0D01*
G01X141138Y324801D01*
G03X141280Y324742I142J141D01*
G01X155827D01*
G02X155969Y324683I0J-200D01*
G01X157907Y322745D01*
X157935Y322689D01*
X157940Y322657D01*
G03X159091Y320567I3460J543D01*
G02X159159Y320417I-132J-150D01*
G01Y304399D01*
G02X159100Y304257I-200J0D01*
G01X148542Y293699D01*
G03X148483Y293557I141J-142D01*
G01Y268683D01*
G02X148424Y268541I-200J0D01*
G01X147342Y267459D01*
G02X147200Y267400I-142J141D01*
G01X34683D01*
G02X34541Y267459I0J200D01*
G01X33359Y268641D01*
G02X33300Y268783I141J142D01*
G01Y302317D01*
G02X33359Y302459I200J0D01*
G01X35941Y305041D01*
G02X36083Y305100I142J-141D01*
G01X45965D01*
G03X46107Y305159I0J200D01*
G01X66581Y325633D01*
G03X66640Y325775I-141J142D01*
G01Y352507D01*
G02X66656Y352585I200J0D01*
G03Y355339I-3221J1377D01*
G02X66640Y355417I184J78D01*
G01Y455154D01*
G02X66699Y455296I200J0D01*
G01X68935Y457532D01*
G02X69077Y457591I142J-141D01*
G37*
G36*
G01X107083Y264500D02*
X127917D01*
G02X128059Y264441I0J-200D01*
G01X136873Y255627D01*
X136903Y255550D01*
X136901Y255507D01*
G03X136898Y255360I3499J-145D01*
G03X140400Y251858I3502J0D01*
G03X140547Y251861I2J3502D01*
G01X140590Y251863D01*
X140667Y251833D01*
X151649Y240851D01*
X151678Y240763D01*
X151672Y240716D01*
G03X151638Y240230I3468J-487D01*
G03X155140Y236728I3502J0D01*
G03X155626Y236762I-1J3502D01*
G01X155673Y236768D01*
X155761Y236739D01*
X156941Y235559D01*
G02X157000Y235417I-141J-142D01*
G01Y233438D01*
X156998Y233436D01*
Y222081D01*
G02X156940Y221940I-200J0D01*
G01X152059Y217059D01*
G02X151917Y217000I-142J141D01*
G01X118583D01*
G02X118441Y217059I0J200D01*
G01X106059Y229441D01*
G02X106000Y229583I141J142D01*
G01Y263417D01*
G02X106059Y263559I200J0D01*
G01X106941Y264441D01*
G02X107083Y264500I142J-141D01*
G37*
G36*
G01X165099Y290118D02*
X478299D01*
G02X478441Y290059I0J-200D01*
G01X481441Y287059D01*
G02X481500Y286917I-141J-142D01*
G01Y269583D01*
G03X481559Y269441I200J0D01*
G01X491591Y259409D01*
G03X491733Y259350I142J141D01*
G01X560767D01*
G03X560909Y259409I0J200D01*
G01X563778Y262278D01*
X563820Y262303D01*
X563845Y262310D01*
G03X567504Y267204I-1443J4894D01*
G03X566544Y270182I-5102J-1D01*
G01X566507Y270234D01*
X566506Y270361D01*
X566796Y270775D01*
X566916Y270818D01*
X566978Y270801D01*
G03X568780Y270552I1803J6403D01*
G03X562128Y277204I0J6652D01*
G03X563734Y272870I6651J0D01*
G01X563776Y272821D01*
X563787Y272694D01*
X563534Y272257D01*
X563419Y272204D01*
X563356Y272216D01*
G03X563329Y272221I-943J-5014D01*
G01X563298Y272227D01*
X563246Y272254D01*
X560059Y275441D01*
G02X560000Y275583I141J142D01*
G01Y284417D01*
G02X560059Y284559I200J0D01*
G01X563941Y288441D01*
G02X564083Y288500I142J-141D01*
G01X628417D01*
G02X628559Y288441I0J-200D01*
G01X632941Y284059D01*
G02X633000Y283917I-141J-142D01*
G01Y266583D01*
G03X633059Y266441I200J0D01*
G01X640091Y259409D01*
G03X640233Y259350I142J141D01*
G01X691769D01*
G02X691910Y259291I-1J-200D01*
G01X698151Y253051D01*
G03X700100Y252244I1949J1950D01*
G01X717100D01*
G03X719049Y253051I0J2757D01*
G01X725290Y259291D01*
G02X725431Y259350I142J-141D01*
G01X786403D01*
X786516Y259251D01*
X786525Y259175D01*
G03X793475I3475J437D01*
G01X793484Y259251D01*
X793597Y259350D01*
X794249D01*
X794363Y259248D01*
X794371Y259171D01*
G03X797854Y256037I3483J368D01*
G03X800382Y257115I0J3503D01*
G01X800410Y257145D01*
X800485Y257177D01*
X800857Y257176D01*
X800932Y257144D01*
X800960Y257114D01*
G03X803500Y256023I2540J2411D01*
G03X806157Y257244I0J3501D01*
G01X806186Y257278D01*
X806267Y257314D01*
X806664Y257308D01*
X806744Y257269D01*
X806772Y257234D01*
G03X809500Y255928I2728J2196D01*
G03X812992Y259165I0J3502D01*
G01X812998Y259244D01*
X813112Y259350D01*
X822563D01*
G02X822749Y259224I0J-200D01*
G03X826000Y257023I3251J1300D01*
G03X828296Y257881I0J3501D01*
G02X828429Y257930I131J-151D01*
G01X828546Y257929D01*
G02X828677Y257879I-1J-200D01*
G03X831000Y256998I2323J2622D01*
G03X833310Y257868I0J3502D01*
G02X833441Y257917I131J-151D01*
G01X833559D01*
G02X833690Y257868I0J-200D01*
G03X836000Y256998I2310J2632D01*
G01X836001D01*
G03X837794Y257492I0J3502D01*
G01X837853Y257528D01*
X837989Y257511D01*
X840941Y254559D01*
G02X841000Y254417I-141J-142D01*
G01Y180083D01*
G02X840941Y179941I-200J0D01*
G01X837059Y176059D01*
G02X836917Y176000I-142J141D01*
G01X805759D01*
G03X805617Y175941I0J-200D01*
G01X798235Y168559D01*
G03X798176Y168417I141J-142D01*
G01Y88161D01*
G02X798117Y88019I-200J0D01*
G01X790176Y80078D01*
G02X790034Y80019I-142J141D01*
G01X650600D01*
X643500Y72919D01*
Y9800D01*
X641200Y7500D01*
X146983D01*
G02X146841Y7559I0J200D01*
G01X141179Y13221D01*
G02X141120Y13363I141J142D01*
G01Y120438D01*
G03X141061Y120580I-200J0D01*
G01X126700Y134941D01*
X126659D01*
Y193400D01*
X142380Y209120D01*
X156299D01*
X159500Y212321D01*
Y232400D01*
X160500Y233400D01*
X166700D01*
X168800Y231300D01*
Y216600D01*
X176100Y209300D01*
X183332D01*
G03X184349Y209149I1017J3351D01*
G03X185366Y209300I0J3502D01*
G01X186500D01*
X188100Y210900D01*
Y229200D01*
X175400Y241900D01*
Y252300D01*
X160000Y267700D01*
Y285019D01*
G02X160059Y285160I200J-1D01*
G01X164958Y290059D01*
G02X165099Y290118I142J-141D01*
G37*
G36*
G01X895062Y569699D02*
X1079936D01*
G02X1080078Y569640I0J-200D01*
G01X1082543Y567175D01*
G02X1082602Y567033I-141J-142D01*
G01Y377070D01*
G02X1082506Y376900I-200J1D01*
G01X1082169Y376694D01*
X1082067Y376690D01*
X1082019Y376715D01*
G03X1080418Y377102I-1600J-3115D01*
G03Y370098I0J-3502D01*
G03X1082019Y370485I1J3502D01*
G01X1082067Y370510D01*
X1082169Y370506D01*
X1082506Y370300D01*
G02X1082602Y370130I-104J-171D01*
G01Y367822D01*
G02X1082543Y367681I-200J1D01*
G01X1077007Y362145D01*
G03X1076948Y362003I141J-142D01*
G01Y349997D01*
G03X1077007Y349855I200J0D01*
G01X1082543Y344319D01*
G02X1082602Y344178I-141J-142D01*
G01Y245685D01*
G02X1082543Y245543I-200J0D01*
G01X1078559Y241559D01*
G02X1078417Y241500I-142J141D01*
G01X1008283D01*
G02X1008141Y241559I0J200D01*
G01X999259Y250441D01*
G03X999117Y250500I-142J-141D01*
G01X959849D01*
G02X959707Y250559I0J200D01*
G01X956025Y254241D01*
G02X955966Y254383I141J142D01*
G01Y362451D01*
G03X955907Y362593I-200J0D01*
G01X955751Y362749D01*
G02X955692Y362899I141J142D01*
G01X955705Y363235D01*
X955741Y363309D01*
X955774Y363336D01*
G03X957002Y366000I-2274J2663D01*
G03X953500Y369502I-3502J0D01*
G03X952081Y369202I-1J-3502D01*
G02X951919I-81J182D01*
G03X950500Y369502I-1418J-3202D01*
G03X949208Y369255I0J-3503D01*
G02X949135Y369241I-74J186D01*
G01X945365D01*
G02X945292Y369255I1J200D01*
G03X942708I-1292J-3256D01*
G01X942673Y369241D01*
X942327D01*
X942292Y369255D01*
G03X939708I-1292J-3256D01*
G02X939635Y369241I-74J186D01*
G01X935865D01*
G02X935792Y369255I1J200D01*
G03X933208I-1292J-3256D01*
G01X933173Y369241D01*
X932827D01*
X932792Y369255D01*
G03X930208I-1292J-3256D01*
G02X930135Y369241I-74J186D01*
G01X926365D01*
G02X926292Y369255I1J200D01*
G03X923708I-1292J-3256D01*
G01X923673Y369241D01*
X923327D01*
X923292Y369255D01*
G03X920708I-1292J-3256D01*
G02X920635Y369241I-74J186D01*
G01X916865D01*
G02X916792Y369255I1J200D01*
G03X914208I-1292J-3256D01*
G01X914173Y369241D01*
X913827D01*
X913792Y369255D01*
G03X911208I-1292J-3256D01*
G02X911135Y369241I-74J186D01*
G01X907365D01*
G02X907292Y369255I1J200D01*
G03X904708I-1292J-3256D01*
G01X904673Y369241D01*
X904327D01*
X904292Y369255D01*
G03X901708I-1292J-3256D01*
G02X901635Y369241I-74J186D01*
G01X897865D01*
G02X897792Y369255I1J200D01*
G03X895208I-1292J-3256D01*
G01X895173Y369241D01*
X894827D01*
X894792Y369255D01*
G03X892208I-1292J-3256D01*
G02X892135Y369241I-74J186D01*
G01X888365D01*
G02X888292Y369255I1J200D01*
G03X885708I-1292J-3256D01*
G01X885673Y369241D01*
X885327D01*
X885292Y369255D01*
G03X882708I-1292J-3256D01*
G02X882635Y369241I-74J186D01*
G01X878865D01*
G02X878792Y369255I1J200D01*
G03X876208I-1292J-3256D01*
G01X876173Y369241D01*
X875827D01*
X875792Y369255D01*
G03X873208I-1292J-3256D01*
G02X873135Y369241I-74J186D01*
G01X869865D01*
G02X869792Y369255I1J200D01*
G03X867208I-1292J-3256D01*
G01X867173Y369241D01*
X866827D01*
X866792Y369255D01*
G03X864208I-1292J-3256D01*
G02X864135Y369241I-74J186D01*
G01X860865D01*
G02X860792Y369255I1J200D01*
G03X858208I-1292J-3256D01*
G01X858173Y369241D01*
X857827D01*
X857792Y369255D01*
G03X855208I-1292J-3256D01*
G02X855135Y369241I-74J186D01*
G01X851865D01*
G02X851792Y369255I1J200D01*
G03X849208I-1292J-3256D01*
G01X849173Y369241D01*
X848827D01*
X848792Y369255D01*
G03X846208I-1292J-3256D01*
G02X846135Y369241I-74J186D01*
G01X800281D01*
G02X800177Y369271I1J200D01*
G03X798475Y369752I-1702J-2771D01*
G01X749414D01*
G02X749341Y369765I-2J200D01*
G03X748075Y370002I-1266J-3265D01*
G03X746809Y369765I0J-3502D01*
G02X746736Y369752I-71J187D01*
G01X653500D01*
G03X651798Y369271I0J-3252D01*
G02X651694Y369241I-105J170D01*
G01X625074D01*
G03X624932Y369182I0J-200D01*
G01X586059Y330309D01*
G02X585917Y330250I-142J141D01*
G01X151672D01*
G02X151530Y330309I0J200D01*
G01X149159Y332680D01*
G02X149100Y332822I141J142D01*
G01Y456199D01*
G02X149159Y456341I200J0D01*
G01X150259Y457441D01*
G02X150401Y457500I142J-141D01*
G01X882627D01*
G03X882769Y457559I0J200D01*
G01X889561Y464351D01*
G03X889620Y464493I-141J142D01*
G01Y564257D01*
G02X889679Y564399I200J0D01*
G01X894920Y569640D01*
G02X895062Y569699I142J-141D01*
G37*
G36*
G01X153583Y570869D02*
X874368D01*
G02X874510Y570810I0J-200D01*
G01X876941Y568379D01*
G02X877000Y568237I-141J-142D01*
G01Y567042D01*
G02X876817Y566843I-200J0D01*
G03Y550397I693J-8223D01*
G02X877000Y550198I-17J-199D01*
G01Y463443D01*
X876970Y463369D01*
X876941Y463341D01*
X874916Y461316D01*
X874888Y461287D01*
X874814Y461257D01*
X761919D01*
G02X761864Y461265I1J200D01*
G01X761839Y461272D01*
X761815Y461286D01*
G03X761710Y461316I-105J-170D01*
G01X149971D01*
G02X149829Y461375I0J200D01*
G01X147822Y463381D01*
G02X147763Y463523I141J142D01*
G01Y558041D01*
G02X147777Y558114I200J-1D01*
G01X147807Y558189D01*
Y558190D01*
G03X147822Y558265I-185J76D01*
G01Y565148D01*
X147852Y565222D01*
X147881Y565250D01*
X153441Y570810D01*
G02X153583Y570869I142J-141D01*
G37*
G36*
G01X561200Y278761D02*
X562155Y277806D01*
G03X562128Y277211I6625J-599D01*
G01Y277204D01*
G03X568780Y270552I6652J0D01*
G03X573472Y272489I0J6651D01*
G01X577961Y268000D01*
Y262000D01*
X575961Y260000D01*
X568061D01*
X567161Y260900D01*
Y266549D01*
X566506Y267204D01*
G03X562402Y271308I-4104J0D01*
G03X561975Y271286I-3J-4104D01*
G01X558775D01*
X557561Y272500D01*
Y277200D01*
Y285461D01*
X560600Y288500D01*
X564083D01*
Y285683D01*
X561200Y282800D01*
Y278761D01*
G37*
G36*
G01X1100383Y573100D02*
X1274717D01*
G02X1274859Y573041I0J-200D01*
G01X1285441Y562459D01*
G02X1285500Y562317I-141J-142D01*
G01Y19083D01*
G02X1285441Y18941I-200J0D01*
G01X1272568Y6068D01*
G02X1272426Y6009I-142J141D01*
G01X654574D01*
G02X654432Y6068I0J200D01*
G01X650859Y9641D01*
G02X650800Y9783I141J142D01*
G01Y68917D01*
G02X650859Y69059I200J0D01*
G01X655697Y73897D01*
G02X655839Y73956I142J-141D01*
G01X791421D01*
G03X791563Y74015I0J200D01*
G01X802441Y84893D01*
G03X802500Y85035I-141J142D01*
G01Y164917D01*
G02X802559Y165059I200J0D01*
G01X807441Y169941D01*
G02X807583Y170000I142J-141D01*
G01X911417D01*
G03X911559Y170059I0J200D01*
G01X920441Y178941D01*
G02X920583Y179000I142J-141D01*
G01X925447D01*
G02X925589Y178941I0J-200D01*
G01X1002091Y102439D01*
G03X1002233Y102380I142J141D01*
G01X1018808D01*
G02X1019008Y102180I0J-200D01*
G01Y100611D01*
G03X1019377Y99723I1256J1D01*
G01X1020918Y98182D01*
G03X1021806Y97814I888J887D01*
G01X1023988D01*
G03X1024876Y98182I0J1255D01*
G01X1029016Y102321D01*
G02X1029158Y102380I142J-141D01*
G01X1084537D01*
G02X1084679Y102321I0J-200D01*
G01X1085859Y101141D01*
X1085868Y100990D01*
X1085820Y100930D01*
G03X1085498Y100000I1180J-929D01*
G03X1087000Y98498I1502J0D01*
G03X1087777Y98715I-1J1502D01*
G01X1087801Y98729D01*
X1087853Y98744D01*
X1088000D01*
G03X1088888Y99112I0J1255D01*
G01X1091818Y102041D01*
G02X1091960Y102100I142J-141D01*
G01X1147440D01*
G02X1147582Y102041I0J-200D01*
G01X1157520Y92103D01*
X1157543Y91983D01*
X1157518Y91926D01*
G03X1157198Y90400I3482J-1527D01*
G03X1161000Y94202I3802J0D01*
G03X1159474Y93882I1J-3802D01*
G01X1159417Y93857D01*
X1159297Y93880D01*
X1151964Y101213D01*
X1151985Y101263D01*
G03X1152000Y101340I-185J76D01*
G01Y111349D01*
G02X1152059Y111491I200J0D01*
G01X1169471Y128903D01*
G03X1169530Y129045I-141J142D01*
G01Y145621D01*
G02X1169589Y145763I200J0D01*
G01X1171249Y147423D01*
G02X1171391Y147482I142J-141D01*
G01X1191699D01*
G03X1191841Y147541I0J200D01*
G01X1194296Y149996D01*
G03X1194355Y150138I-141J142D01*
G01Y204272D01*
G02X1194414Y204414I200J0D01*
G01X1210027Y220027D01*
G03X1210086Y220169I-141J142D01*
G01Y287825D01*
G02X1210145Y287967I200J0D01*
G01X1216941Y294763D01*
G02X1217083Y294822I142J-141D01*
G01X1265217D01*
G03X1265359Y294881I0J200D01*
G01X1270130Y299652D01*
G03X1270189Y299794I-141J142D01*
G01Y480917D01*
G03X1270130Y481059I-200J0D01*
G01X1261848Y489341D01*
G03X1261706Y489400I-142J-141D01*
G01X1190611D01*
G02X1190469Y489459I0J200D01*
G01X1182100Y497828D01*
G02X1182041Y497970I141J142D01*
G01Y518776D01*
G03X1181982Y518918I-200J0D01*
G01X1173559Y527341D01*
G03X1173417Y527400I-142J-141D01*
G01X1102583D01*
G02X1102441Y527459I0J200D01*
G01X1098059Y531841D01*
G02X1098000Y531983I141J142D01*
G01Y570717D01*
G02X1098059Y570859I200J0D01*
G01X1100241Y573041D01*
G02X1100383Y573100I142J-141D01*
G37*
G36*
G01X1086100Y404600D02*
X1094900D01*
X1095500Y404000D01*
Y364000D01*
X1094500Y363000D01*
X1086964D01*
X1083000Y359036D01*
Y352564D01*
X1089820Y345744D01*
Y237307D01*
X1085063Y232550D01*
X1038550D01*
X1013000Y207000D01*
Y174964D01*
X1021500Y166464D01*
Y165000D01*
X1020793Y164293D01*
X1016807D01*
X1007986Y173114D01*
Y209486D01*
X1034600Y236100D01*
X1083400D01*
X1086270Y238970D01*
Y344130D01*
X1079450Y350950D01*
Y361050D01*
X1085300Y366900D01*
Y403800D01*
X1086100Y404600D01*
G37*
G36*
G01X1088000Y360500D02*
X1094420D01*
X1097000Y357920D01*
Y233906D01*
X1088144Y225050D01*
X1044006D01*
X1023300Y204344D01*
Y170800D01*
X1022600Y170100D01*
X1021400D01*
X1020300Y171200D01*
Y208415D01*
X1041935Y230050D01*
X1086099D01*
X1092320Y236271D01*
Y346780D01*
X1085500Y353600D01*
Y358000D01*
X1088000Y360500D01*
G37*
G36*
G01X1056113Y148500D02*
X1072917D01*
G02X1073059Y148441I0J-200D01*
G01X1074441Y147059D01*
G02X1074500Y146917I-141J-142D01*
G01Y135583D01*
G02X1074441Y135441I-200J0D01*
G01X1073559Y134559D01*
G02X1073417Y134500I-142J141D01*
G01X1059017D01*
X1058918Y134564D01*
X1058894Y134618D01*
G03X1056156I-1369J-618D01*
G01X1056132Y134564D01*
X1056033Y134500D01*
X1043583D01*
G02X1043441Y134559I0J200D01*
G01X1042559Y135441D01*
G02X1042500Y135583I141J142D01*
G01Y147417D01*
G02X1042559Y147559I200J0D01*
G01X1043441Y148441D01*
G02X1043583Y148500I142J-141D01*
G01X1052887D01*
X1052999Y148400D01*
X1053008Y148324D01*
G03X1055992I1492J176D01*
G01X1056001Y148400D01*
X1056113Y148500D01*
G37*
G36*
G01X1101287Y377500D02*
X1161800D01*
X1162400Y376900D01*
Y328700D01*
X1166615Y324485D01*
Y240815D01*
X1165300Y239500D01*
X1101700D01*
X1099744Y241456D01*
Y375956D01*
X1101287Y377500D01*
G37*
G36*
G01Y520000D02*
X1160600D01*
X1163000Y517600D01*
Y465600D01*
X1166615Y461985D01*
Y383315D01*
X1165300Y382000D01*
X1100000D01*
X1098420Y383580D01*
Y517133D01*
X1101287Y520000D01*
G37*
G36*
G01X1184409Y477307D02*
X1186144Y479042D01*
G02X1186286Y479101I142J-141D01*
G01X1257488D01*
G02X1257630Y479042I0J-200D01*
G01X1261441Y475231D01*
G02X1261500Y475089I-141J-142D01*
G01Y303583D01*
G02X1261441Y303441I-200J0D01*
G01X1258559Y300559D01*
G02X1258417Y300500I-142J141D01*
G01X1214424D01*
G03X1214282Y300441I0J-200D01*
G01X1205420Y291579D01*
G02X1205278Y291520I-142J141D01*
G01X1191273D01*
G02X1191131Y291579I0J200D01*
G01X1190859Y291851D01*
G02X1190800Y291993I141J142D01*
G01Y373117D01*
G03X1190741Y373259I-200J0D01*
G01X1184409Y379591D01*
G02X1184350Y379733I141J142D01*
G01Y477165D01*
G02X1184409Y477307I200J0D01*
G37*
%LPC*%
G75*
G36*
G01X36402Y275743D02*
Y276146D01*
X36363Y276227D01*
X36328Y276256D01*
G02X34878Y279291I2451J3035D01*
G02X42682I3902J0D01*
G02X41232Y276256I-3901J0D01*
G01X41197Y276227D01*
X41158Y276146D01*
Y275743D01*
X41197Y275662D01*
X41232Y275633D01*
G02X42682Y272598I-2451J-3035D01*
G02X34878I-3902J0D01*
G02X36328Y275633I3901J0D01*
G01X36363Y275662D01*
X36402Y275743D01*
G37*
G36*
G01X46402D02*
Y276146D01*
X46363Y276227D01*
X46328Y276256D01*
G02X44878Y279291I2451J3035D01*
G02X52682I3902J0D01*
G02X51232Y276256I-3901J0D01*
G01X51197Y276227D01*
X51158Y276146D01*
Y275743D01*
X51197Y275662D01*
X51232Y275633D01*
G02X52682Y272598I-2451J-3035D01*
G02X44878I-3902J0D01*
G02X46328Y275633I3901J0D01*
G01X46363Y275662D01*
X46402Y275743D01*
G37*
G36*
G01X36402Y295743D02*
Y296146D01*
X36363Y296227D01*
X36328Y296256D01*
G02X34878Y299291I2451J3035D01*
G02X42682I3902J0D01*
G02X41232Y296256I-3901J0D01*
G01X41197Y296227D01*
X41158Y296146D01*
Y295743D01*
X41197Y295662D01*
X41232Y295633D01*
G02X42682Y292598I-2451J-3035D01*
G02X34878I-3902J0D01*
G02X36328Y295633I3901J0D01*
G01X36363Y295662D01*
X36402Y295743D01*
G37*
G36*
G01X46402D02*
Y296146D01*
X46363Y296227D01*
X46328Y296256D01*
G02X44878Y299291I2451J3035D01*
G02X52682I3902J0D01*
G02X51232Y296256I-3901J0D01*
G01X51197Y296227D01*
X51158Y296146D01*
Y295743D01*
X51197Y295662D01*
X51232Y295633D01*
G02X52682Y292598I-2451J-3035D01*
G02X44878I-3902J0D01*
G02X46328Y295633I3901J0D01*
G01X46363Y295662D01*
X46402Y295743D01*
G37*
G36*
G01X194341Y248302D02*
G02X195760Y248602I1418J-3202D01*
G02X197179Y248302I1J-3502D01*
G03X197341I81J182D01*
G02X198760Y248602I1418J-3202D01*
G02X200179Y248302I1J-3502D01*
G03X200341I81J182D01*
G02X201758Y248602I1418J-3202D01*
G01X201760D01*
G02X205262Y245100I0J-3502D01*
G01Y245098D01*
G02X204962Y243681I-3502J1D01*
G03Y243519I182J-81D01*
G02X205262Y242102I-3202J-1418D01*
G01Y242100D01*
G02X201760Y238598I-3502J0D01*
G01X201758D01*
G02X200341Y238898I1J3502D01*
G03X200179I-81J-182D01*
G02X198760Y238598I-1418J3202D01*
G02X197341Y238898I-1J3502D01*
G03X197179I-81J-182D01*
G02X195760Y238598I-1418J3202D01*
G02X194341Y238898I-1J3502D01*
G03X194179I-81J-182D01*
G02X192760Y238598I-1418J3202D01*
G02X191341Y238898I-1J3502D01*
G03X191179I-81J-182D01*
G02X189762Y238598I-1418J3202D01*
G01X189760D01*
G02X186258Y242100I0J3502D01*
G01Y242102D01*
G02X186558Y243519I3502J-1D01*
G03Y243681I-182J81D01*
G02X186258Y245098I3202J1418D01*
G01Y245100D01*
G02X189760Y248602I3502J0D01*
G01X189762D01*
G02X191179Y248302I-1J-3502D01*
G03X191341I81J182D01*
G02X192760Y248602I1418J-3202D01*
G02X194179Y248302I1J-3502D01*
G03X194341I81J182D01*
G37*
G36*
G01X343583Y281960D02*
X344015D01*
X344102Y282007D01*
X344130Y282048D01*
G02X351299Y285856I7169J-4844D01*
G02X359951Y277204I0J-8652D01*
G02X358709Y272738I-8652J0D01*
G01X358685Y272697D01*
X358677Y272603D01*
X358835Y272218D01*
X358906Y272156D01*
X358952Y272144D01*
G02X361328Y270768I-1275J-4940D01*
G01X361357Y270738D01*
X361430Y270708D01*
X361798D01*
X361871Y270738D01*
X361900Y270768D01*
G02X369202I3651J-3564D01*
G01X369231Y270738D01*
X369304Y270708D01*
X369672D01*
X369745Y270738D01*
X369774Y270768D01*
G02X377076I3651J-3564D01*
G01X377105Y270738D01*
X377178Y270708D01*
X377546D01*
X377619Y270738D01*
X377648Y270768D01*
G02X384950I3651J-3564D01*
G01X384979Y270738D01*
X385052Y270708D01*
X385420D01*
X385493Y270738D01*
X385522Y270768D01*
G02X392824I3651J-3564D01*
G01X392853Y270738D01*
X392926Y270708D01*
X393294D01*
X393367Y270738D01*
X393396Y270768D01*
G02X400698I3651J-3564D01*
G01X400727Y270738D01*
X400800Y270708D01*
X401168D01*
X401241Y270738D01*
X401270Y270768D01*
G02X404921Y272306I3651J-3564D01*
G02X405875Y272216I0J-5101D01*
G01X405938Y272204D01*
X406053Y272257D01*
X406306Y272694D01*
X406295Y272821D01*
X406253Y272870D01*
G02X404647Y277204I5045J4334D01*
G02X411299Y270552I6652J0D01*
G02X409497Y270801I1J6652D01*
G01X409435Y270818D01*
X409315Y270775D01*
X409025Y270361D01*
X409026Y270234D01*
X409063Y270182D01*
G02X410023Y267204I-4142J-2979D01*
G02X404921Y262102I-5102J0D01*
G02X401270Y263640I0J5102D01*
G01X401241Y263670D01*
X401168Y263700D01*
X400800D01*
X400727Y263670D01*
X400698Y263640D01*
G02X393396I-3651J3564D01*
G01X393367Y263670D01*
X393294Y263700D01*
X392926D01*
X392853Y263670D01*
X392824Y263640D01*
G02X385522I-3651J3564D01*
G01X385493Y263670D01*
X385420Y263700D01*
X385052D01*
X384979Y263670D01*
X384950Y263640D01*
G02X377648I-3651J3564D01*
G01X377619Y263670D01*
X377546Y263700D01*
X377178D01*
X377105Y263670D01*
X377076Y263640D01*
G02X369774I-3651J3564D01*
G01X369745Y263670D01*
X369672Y263700D01*
X369304D01*
X369231Y263670D01*
X369202Y263640D01*
G02X361900I-3651J3564D01*
G01X361871Y263670D01*
X361798Y263700D01*
X361430D01*
X361357Y263670D01*
X361328Y263640D01*
G02X357677Y262102I-3651J3564D01*
G02X352575Y267204I0J5102D01*
G02X352660Y268131I5102J0D01*
G01X352669Y268178D01*
X352642Y268269D01*
X352360Y268573D01*
X352271Y268607D01*
X352224Y268602D01*
G02X351299Y268552I-929J8602D01*
G02X344130Y272360I0J8652D01*
G01X344102Y272401D01*
X344015Y272448D01*
X343583D01*
X343496Y272401D01*
X343468Y272360D01*
G02X336299Y268552I-7169J4844D01*
G02Y285856I0J8652D01*
G02X343468Y282048I0J-8652D01*
G01X343496Y282007D01*
X343583Y281960D01*
G37*
G36*
G01X186103D02*
X186535D01*
X186622Y282007D01*
X186650Y282048D01*
G02X193819Y285856I7169J-4844D01*
G02X202471Y277204I0J-8652D01*
G02X201229Y272738I-8652J0D01*
G01X201205Y272697D01*
X201197Y272603D01*
X201355Y272218D01*
X201426Y272156D01*
X201472Y272144D01*
G02X203848Y270768I-1275J-4940D01*
G01X203877Y270738D01*
X203950Y270708D01*
X204318D01*
X204391Y270738D01*
X204420Y270768D01*
G02X211722I3651J-3564D01*
G01X211751Y270738D01*
X211824Y270708D01*
X212192D01*
X212265Y270738D01*
X212294Y270768D01*
G02X219596I3651J-3564D01*
G01X219625Y270738D01*
X219698Y270708D01*
X220066D01*
X220139Y270738D01*
X220168Y270768D01*
G02X227470I3651J-3564D01*
G01X227499Y270738D01*
X227572Y270708D01*
X227940D01*
X228013Y270738D01*
X228042Y270768D01*
G02X235344I3651J-3564D01*
G01X235373Y270738D01*
X235446Y270708D01*
X235814D01*
X235887Y270738D01*
X235916Y270768D01*
G02X243218I3651J-3564D01*
G01X243247Y270738D01*
X243320Y270708D01*
X243688D01*
X243761Y270738D01*
X243790Y270768D01*
G02X247441Y272306I3651J-3564D01*
G02X248395Y272216I0J-5101D01*
G01X248458Y272204D01*
X248573Y272257D01*
X248826Y272694D01*
X248815Y272821D01*
X248773Y272870D01*
G02X247167Y277204I5045J4334D01*
G02X253819Y270552I6652J0D01*
G02X252017Y270801I1J6652D01*
G01X251955Y270818D01*
X251835Y270775D01*
X251545Y270361D01*
X251546Y270234D01*
X251583Y270182D01*
G02X252543Y267204I-4142J-2979D01*
G02X247441Y262102I-5102J0D01*
G02X243790Y263640I0J5102D01*
G01X243761Y263670D01*
X243688Y263700D01*
X243320D01*
X243247Y263670D01*
X243218Y263640D01*
G02X235916I-3651J3564D01*
G01X235887Y263670D01*
X235814Y263700D01*
X235446D01*
X235373Y263670D01*
X235344Y263640D01*
G02X228042I-3651J3564D01*
G01X228013Y263670D01*
X227940Y263700D01*
X227572D01*
X227499Y263670D01*
X227470Y263640D01*
G02X220168I-3651J3564D01*
G01X220139Y263670D01*
X220066Y263700D01*
X219698D01*
X219625Y263670D01*
X219596Y263640D01*
G02X212294I-3651J3564D01*
G01X212265Y263670D01*
X212192Y263700D01*
X211824D01*
X211751Y263670D01*
X211722Y263640D01*
G02X204420I-3651J3564D01*
G01X204391Y263670D01*
X204318Y263700D01*
X203950D01*
X203877Y263670D01*
X203848Y263640D01*
G02X200197Y262102I-3651J3564D01*
G02X195095Y267204I0J5102D01*
G02X195180Y268131I5102J0D01*
G01X195189Y268178D01*
X195162Y268269D01*
X194880Y268573D01*
X194791Y268607D01*
X194744Y268602D01*
G02X193819Y268552I-929J8602D01*
G02X186650Y272360I0J8652D01*
G01X186622Y272401D01*
X186535Y272448D01*
X186103D01*
X186016Y272401D01*
X185988Y272360D01*
G02X178819Y268552I-7169J4844D01*
G02Y285856I0J8652D01*
G02X185988Y282048I0J-8652D01*
G01X186016Y282007D01*
X186103Y281960D01*
G37*
G36*
G01X242183Y239512D02*
G02X238998Y243000I317J3488D01*
G02X239719Y245128I3501J0D01*
G03Y245372I-159J122D01*
G02X238998Y247500I2780J2128D01*
G02X246002I3502J0D01*
G02X245281Y245372I-3501J0D01*
G03Y245128I159J-122D01*
G02X246002Y243000I-2780J-2128D01*
G02X245958Y242449I-3502J2D01*
G01X245952Y242408D01*
X245972Y242328D01*
X246203Y242031D01*
X246275Y241991D01*
X246317Y241988D01*
G02X249502Y238500I-317J-3488D01*
G02X249202Y237081I-3502J-1D01*
G03Y236919I182J-81D01*
G02X249502Y235500I-3202J-1418D01*
G02X242498I-3502J0D01*
G02X242798Y236919I3502J1D01*
G03Y237081I-182J81D01*
G02X242498Y238500I3202J1418D01*
G02X242542Y239051I3502J-2D01*
G01X242548Y239092D01*
X242528Y239172D01*
X242297Y239469D01*
X242225Y239509D01*
X242183Y239512D01*
G37*
G36*
G01X709164Y240012D02*
G02X705979Y243500I317J3488D01*
G02X706404Y245172I3501J0D01*
G03X706405Y245361I-176J95D01*
G02X705998Y247000I3095J1639D01*
G02X713002I3502J0D01*
G02X712577Y245328I-3501J0D01*
G03X712576Y245139I176J-95D01*
G02X712983Y243500I-3095J-1639D01*
G02X712939Y242949I-3502J2D01*
G01X712933Y242908D01*
X712953Y242828D01*
X713184Y242531D01*
X713256Y242491D01*
X713298Y242488D01*
G02X716483Y239000I-317J-3488D01*
G02X716183Y237581I-3502J-1D01*
G03Y237419I182J-81D01*
G02X716483Y236000I-3202J-1418D01*
G02X709479I-3502J0D01*
G02X709779Y237419I3502J1D01*
G03Y237581I-182J81D01*
G02X709479Y239000I3202J1418D01*
G02X709523Y239551I3502J-2D01*
G01X709529Y239592D01*
X709509Y239672D01*
X709278Y239969D01*
X709206Y240009D01*
X709164Y240012D01*
G37*
G36*
G01X551683D02*
G02X548498Y243500I317J3488D01*
G02X548914Y245155I3502J0D01*
G03Y245345I-176J95D01*
G02X548498Y247000I3086J1655D01*
G02X555502I3502J0D01*
G02X555086Y245345I-3502J0D01*
G03Y245155I176J-95D01*
G02X555502Y243500I-3086J-1655D01*
G02X555458Y242949I-3502J2D01*
G01X555452Y242908D01*
X555472Y242828D01*
X555703Y242531D01*
X555775Y242491D01*
X555817Y242488D01*
G02X559002Y239000I-317J-3488D01*
G02X558702Y237581I-3502J-1D01*
G03Y237419I182J-81D01*
G02X559002Y236000I-3202J-1418D01*
G02X551998I-3502J0D01*
G02X552298Y237419I3502J1D01*
G03Y237581I-182J81D01*
G02X551998Y239000I3202J1418D01*
G02X552042Y239551I3502J-2D01*
G01X552048Y239592D01*
X552028Y239672D01*
X551797Y239969D01*
X551725Y240009D01*
X551683Y240012D01*
G37*
G36*
G01X398183Y239012D02*
G02X394998Y242500I317J3488D01*
G02X395719Y244628I3501J0D01*
G03Y244872I-159J122D01*
G02X394998Y247000I2780J2128D01*
G02X402002I3502J0D01*
G02X401281Y244872I-3501J0D01*
G03Y244628I159J-122D01*
G02X402002Y242500I-2780J-2128D01*
G02X401958Y241949I-3502J2D01*
G01X401952Y241908D01*
X401972Y241828D01*
X402203Y241531D01*
X402275Y241491D01*
X402317Y241488D01*
G02X405502Y238000I-317J-3488D01*
G02X405202Y236581I-3502J-1D01*
G03Y236419I182J-81D01*
G02X405502Y235000I-3202J-1418D01*
G02X398498I-3502J0D01*
G02X398798Y236419I3502J1D01*
G03Y236581I-182J81D01*
G02X398498Y238000I3202J1418D01*
G02X398542Y238551I3502J-2D01*
G01X398548Y238592D01*
X398528Y238672D01*
X398297Y238969D01*
X398225Y239009D01*
X398183Y239012D01*
G37*
G36*
G01X423368Y201190D02*
G02X422498Y203500I2632J2310D01*
G02X422704Y204682I3502J-1D01*
G03Y204818I-189J68D01*
G02X422498Y206000I3296J1183D01*
G02X429502I3502J0D01*
G02X429296Y204818I-3502J1D01*
G03Y204682I189J-68D01*
G02X429502Y203500I-3296J-1183D01*
G02X428632Y201190I-3502J0D01*
G03X428583Y201059I151J-131D01*
G01Y200941D01*
G03X428632Y200810I200J0D01*
G02X429502Y198500I-2632J-2310D01*
G02X429296Y197318I-3502J1D01*
G03Y197182I189J-68D01*
G02X429502Y196000I-3296J-1183D01*
G02X422498I-3502J0D01*
G02X422704Y197182I3502J-1D01*
G03Y197318I-189J68D01*
G02X422498Y198500I3296J1183D01*
G02X423368Y200810I3502J0D01*
G03X423417Y200941I-151J131D01*
G01Y201059D01*
G03X423368Y201190I-200J0D01*
G37*
G36*
G01X401868D02*
G02X400998Y203500I2632J2310D01*
G02X401204Y204682I3502J-1D01*
G03Y204818I-189J68D01*
G02X400998Y206000I3296J1183D01*
G02X408002I3502J0D01*
G02X407796Y204818I-3502J1D01*
G03Y204682I189J-68D01*
G02X408002Y203500I-3296J-1183D01*
G02X407132Y201190I-3502J0D01*
G03X407083Y201059I151J-131D01*
G01Y200941D01*
G03X407132Y200810I200J0D01*
G02X408002Y198500I-2632J-2310D01*
G02X407796Y197318I-3502J1D01*
G03Y197182I189J-68D01*
G02X408002Y196000I-3296J-1183D01*
G02X400998I-3502J0D01*
G02X401204Y197182I3502J-1D01*
G03Y197318I-189J68D01*
G02X400998Y198500I3296J1183D01*
G02X401868Y200810I3502J0D01*
G03X401917Y200941I-151J131D01*
G01Y201059D01*
G03X401868Y201190I-200J0D01*
G37*
G36*
G01X380368D02*
G02X379498Y203500I2632J2310D01*
G02X379704Y204682I3502J-1D01*
G03Y204818I-189J68D01*
G02X379498Y206000I3296J1183D01*
G02X386502I3502J0D01*
G02X386296Y204818I-3502J1D01*
G03Y204682I189J-68D01*
G02X386502Y203500I-3296J-1183D01*
G02X385632Y201190I-3502J0D01*
G03X385583Y201059I151J-131D01*
G01Y200941D01*
G03X385632Y200810I200J0D01*
G02X386502Y198500I-2632J-2310D01*
G02X386296Y197318I-3502J1D01*
G03Y197182I189J-68D01*
G02X386502Y196000I-3296J-1183D01*
G02X379498I-3502J0D01*
G02X379704Y197182I3502J-1D01*
G03Y197318I-189J68D01*
G02X379498Y198500I3296J1183D01*
G02X380368Y200810I3502J0D01*
G03X380417Y200941I-151J131D01*
G01Y201059D01*
G03X380368Y201190I-200J0D01*
G37*
G36*
G01X358868D02*
G02X357998Y203500I2632J2310D01*
G02X358204Y204682I3502J-1D01*
G03Y204818I-189J68D01*
G02X357998Y206000I3296J1183D01*
G02X365002I3502J0D01*
G02X364796Y204818I-3502J1D01*
G03Y204682I189J-68D01*
G02X365002Y203500I-3296J-1183D01*
G02X364132Y201190I-3502J0D01*
G03X364083Y201059I151J-131D01*
G01Y200941D01*
G03X364132Y200810I200J0D01*
G02X365002Y198500I-2632J-2310D01*
G02X364796Y197318I-3502J1D01*
G03Y197182I189J-68D01*
G02X365002Y196000I-3296J-1183D01*
G02X357998I-3502J0D01*
G02X358204Y197182I3502J-1D01*
G03Y197318I-189J68D01*
G02X357998Y198500I3296J1183D01*
G02X358868Y200810I3502J0D01*
G03X358917Y200941I-151J131D01*
G01Y201059D01*
G03X358868Y201190I-200J0D01*
G37*
G36*
G01X337368D02*
G02X336498Y203500I2632J2310D01*
G02X336704Y204682I3502J-1D01*
G03Y204818I-189J68D01*
G02X336498Y206000I3296J1183D01*
G02X343502I3502J0D01*
G02X343296Y204818I-3502J1D01*
G03Y204682I189J-68D01*
G02X343502Y203500I-3296J-1183D01*
G02X342632Y201190I-3502J0D01*
G03X342583Y201059I151J-131D01*
G01Y200941D01*
G03X342632Y200810I200J0D01*
G02X343502Y198500I-2632J-2310D01*
G02X343296Y197318I-3502J1D01*
G03Y197182I189J-68D01*
G02X343502Y196000I-3296J-1183D01*
G02X336498I-3502J0D01*
G02X336704Y197182I3502J-1D01*
G03Y197318I-189J68D01*
G02X336498Y198500I3296J1183D01*
G02X337368Y200810I3502J0D01*
G03X337417Y200941I-151J131D01*
G01Y201059D01*
G03X337368Y201190I-200J0D01*
G37*
G36*
G01X315868D02*
G02X314998Y203500I2632J2310D01*
G02X315204Y204682I3502J-1D01*
G03Y204818I-189J68D01*
G02X314998Y206000I3296J1183D01*
G02X322002I3502J0D01*
G02X321796Y204818I-3502J1D01*
G03Y204682I189J-68D01*
G02X322002Y203500I-3296J-1183D01*
G02X321132Y201190I-3502J0D01*
G03X321083Y201059I151J-131D01*
G01Y200941D01*
G03X321132Y200810I200J0D01*
G02X322002Y198500I-2632J-2310D01*
G02X321796Y197318I-3502J1D01*
G03Y197182I189J-68D01*
G02X322002Y196000I-3296J-1183D01*
G02X314998I-3502J0D01*
G02X315204Y197182I3502J-1D01*
G03Y197318I-189J68D01*
G02X314998Y198500I3296J1183D01*
G02X315868Y200810I3502J0D01*
G03X315917Y200941I-151J131D01*
G01Y201059D01*
G03X315868Y201190I-200J0D01*
G37*
G36*
G01X294368D02*
G02X293498Y203500I2632J2310D01*
G02X293704Y204682I3502J-1D01*
G03Y204818I-189J68D01*
G02X293498Y206000I3296J1183D01*
G02X300502I3502J0D01*
G02X300296Y204818I-3502J1D01*
G03Y204682I189J-68D01*
G02X300502Y203500I-3296J-1183D01*
G02X299632Y201190I-3502J0D01*
G03X299583Y201059I151J-131D01*
G01Y200941D01*
G03X299632Y200810I200J0D01*
G02X300502Y198500I-2632J-2310D01*
G02X300296Y197318I-3502J1D01*
G03Y197182I189J-68D01*
G02X300502Y196000I-3296J-1183D01*
G02X293498I-3502J0D01*
G02X293704Y197182I3502J-1D01*
G03Y197318I-189J68D01*
G02X293498Y198500I3296J1183D01*
G02X294368Y200810I3502J0D01*
G03X294417Y200941I-151J131D01*
G01Y201059D01*
G03X294368Y201190I-200J0D01*
G37*
G36*
G01X730858Y200690D02*
G02X729988Y203000I2632J2310D01*
G02X730194Y204182I3502J-1D01*
G03Y204318I-189J68D01*
G02X729988Y205500I3296J1183D01*
G02X736992I3502J0D01*
G02X736786Y204318I-3502J1D01*
G03Y204182I189J-68D01*
G02X736992Y203000I-3296J-1183D01*
G02X736122Y200690I-3502J0D01*
G03X736073Y200559I151J-131D01*
G01Y200441D01*
G03X736122Y200310I200J0D01*
G02X736992Y198000I-2632J-2310D01*
G02X736786Y196818I-3502J1D01*
G03Y196682I189J-68D01*
G02X736992Y195500I-3296J-1183D01*
G02X729988I-3502J0D01*
G02X730194Y196682I3502J-1D01*
G03Y196818I-189J68D01*
G02X729988Y198000I3296J1183D01*
G02X730858Y200310I3502J0D01*
G03X730907Y200441I-151J131D01*
G01Y200559D01*
G03X730858Y200690I-200J0D01*
G37*
G36*
G01X709358D02*
G02X708488Y203000I2632J2310D01*
G02X708694Y204182I3502J-1D01*
G03Y204318I-189J68D01*
G02X708488Y205500I3296J1183D01*
G02X715492I3502J0D01*
G02X715286Y204318I-3502J1D01*
G03Y204182I189J-68D01*
G02X715492Y203000I-3296J-1183D01*
G02X714622Y200690I-3502J0D01*
G03X714573Y200559I151J-131D01*
G01Y200441D01*
G03X714622Y200310I200J0D01*
G02X715492Y198000I-2632J-2310D01*
G02X715286Y196818I-3502J1D01*
G03Y196682I189J-68D01*
G02X715492Y195500I-3296J-1183D01*
G02X708488I-3502J0D01*
G02X708694Y196682I3502J-1D01*
G03Y196818I-189J68D01*
G02X708488Y198000I3296J1183D01*
G02X709358Y200310I3502J0D01*
G03X709407Y200441I-151J131D01*
G01Y200559D01*
G03X709358Y200690I-200J0D01*
G37*
G36*
G01X687868D02*
G02X686998Y203000I2632J2310D01*
G02X687204Y204182I3502J-1D01*
G03Y204318I-189J68D01*
G02X686998Y205500I3296J1183D01*
G02X694002I3502J0D01*
G02X693796Y204318I-3502J1D01*
G03Y204182I189J-68D01*
G02X694002Y203000I-3296J-1183D01*
G02X693132Y200690I-3502J0D01*
G03X693083Y200559I151J-131D01*
G01Y200441D01*
G03X693132Y200310I200J0D01*
G02X694002Y198000I-2632J-2310D01*
G02X693796Y196818I-3502J1D01*
G03Y196682I189J-68D01*
G02X694002Y195500I-3296J-1183D01*
G02X686998I-3502J0D01*
G02X687204Y196682I3502J-1D01*
G03Y196818I-189J68D01*
G02X686998Y198000I3296J1183D01*
G02X687868Y200310I3502J0D01*
G03X687917Y200441I-151J131D01*
G01Y200559D01*
G03X687868Y200690I-200J0D01*
G37*
G36*
G01X666368D02*
G02X665498Y203000I2632J2310D01*
G02X665704Y204182I3502J-1D01*
G03Y204318I-189J68D01*
G02X665498Y205500I3296J1183D01*
G02X672502I3502J0D01*
G02X672296Y204318I-3502J1D01*
G03Y204182I189J-68D01*
G02X672502Y203000I-3296J-1183D01*
G02X671632Y200690I-3502J0D01*
G03X671583Y200559I151J-131D01*
G01Y200441D01*
G03X671632Y200310I200J0D01*
G02X672502Y198000I-2632J-2310D01*
G02X672296Y196818I-3502J1D01*
G03Y196682I189J-68D01*
G02X672502Y195500I-3296J-1183D01*
G02X665498I-3502J0D01*
G02X665704Y196682I3502J-1D01*
G03Y196818I-189J68D01*
G02X665498Y198000I3296J1183D01*
G02X666368Y200310I3502J0D01*
G03X666417Y200441I-151J131D01*
G01Y200559D01*
G03X666368Y200690I-200J0D01*
G37*
G36*
G01X644868D02*
G02X643998Y203000I2632J2310D01*
G02X644204Y204182I3502J-1D01*
G03Y204318I-189J68D01*
G02X643998Y205500I3296J1183D01*
G02X651002I3502J0D01*
G02X650796Y204318I-3502J1D01*
G03Y204182I189J-68D01*
G02X651002Y203000I-3296J-1183D01*
G02X650132Y200690I-3502J0D01*
G03X650083Y200559I151J-131D01*
G01Y200441D01*
G03X650132Y200310I200J0D01*
G02X651002Y198000I-2632J-2310D01*
G02X650796Y196818I-3502J1D01*
G03Y196682I189J-68D01*
G02X651002Y195500I-3296J-1183D01*
G02X643998I-3502J0D01*
G02X644204Y196682I3502J-1D01*
G03Y196818I-189J68D01*
G02X643998Y198000I3296J1183D01*
G02X644868Y200310I3502J0D01*
G03X644917Y200441I-151J131D01*
G01Y200559D01*
G03X644868Y200690I-200J0D01*
G37*
G36*
G01X623368D02*
G02X622498Y203000I2632J2310D01*
G02X622704Y204182I3502J-1D01*
G03Y204318I-189J68D01*
G02X622498Y205500I3296J1183D01*
G02X629502I3502J0D01*
G02X629296Y204318I-3502J1D01*
G03Y204182I189J-68D01*
G02X629502Y203000I-3296J-1183D01*
G02X628632Y200690I-3502J0D01*
G03X628583Y200559I151J-131D01*
G01Y200441D01*
G03X628632Y200310I200J0D01*
G02X629502Y198000I-2632J-2310D01*
G02X629296Y196818I-3502J1D01*
G03Y196682I189J-68D01*
G02X629502Y195500I-3296J-1183D01*
G02X622498I-3502J0D01*
G02X622704Y196682I3502J-1D01*
G03Y196818I-189J68D01*
G02X622498Y198000I3296J1183D01*
G02X623368Y200310I3502J0D01*
G03X623417Y200441I-151J131D01*
G01Y200559D01*
G03X623368Y200690I-200J0D01*
G37*
G36*
G01X601868D02*
G02X600998Y203000I2632J2310D01*
G02X601204Y204182I3502J-1D01*
G03Y204318I-189J68D01*
G02X600998Y205500I3296J1183D01*
G02X608002I3502J0D01*
G02X607796Y204318I-3502J1D01*
G03Y204182I189J-68D01*
G02X608002Y203000I-3296J-1183D01*
G02X607132Y200690I-3502J0D01*
G03X607083Y200559I151J-131D01*
G01Y200441D01*
G03X607132Y200310I200J0D01*
G02X608002Y198000I-2632J-2310D01*
G02X607796Y196818I-3502J1D01*
G03Y196682I189J-68D01*
G02X608002Y195500I-3296J-1183D01*
G02X600998I-3502J0D01*
G02X601204Y196682I3502J-1D01*
G03Y196818I-189J68D01*
G02X600998Y198000I3296J1183D01*
G02X601868Y200310I3502J0D01*
G03X601917Y200441I-151J131D01*
G01Y200559D01*
G03X601868Y200690I-200J0D01*
G37*
G36*
G01X363910Y154463D02*
Y154907D01*
X363861Y154996D01*
X363816Y155023D01*
G02X361243Y159685I2937J4662D01*
G02X366752Y165194I5509J0D01*
G02X371414Y162621I0J-5510D01*
G01X371441Y162576D01*
X371530Y162527D01*
X371974D01*
X372063Y162576D01*
X372090Y162621D01*
G02X376752Y165194I4662J-2937D01*
G02X382261Y159685I0J-5509D01*
G02X379688Y155023I-5510J0D01*
G01X379643Y154996D01*
X379594Y154907D01*
Y154463D01*
X379643Y154374D01*
X379688Y154347D01*
G02Y145023I-2937J-4662D01*
G01X379643Y144996D01*
X379594Y144907D01*
Y144463D01*
X379643Y144374D01*
X379688Y144347D01*
G02Y135023I-2937J-4662D01*
G01X379643Y134996D01*
X379594Y134907D01*
Y134463D01*
X379643Y134374D01*
X379688Y134347D01*
G02X382261Y129685I-2937J-4662D01*
G02X376752Y124176I-5509J0D01*
G02X372090Y126749I0J5510D01*
G01X372063Y126794D01*
X371974Y126843D01*
X371530D01*
X371441Y126794D01*
X371414Y126749D01*
G02X366752Y124176I-4662J2937D01*
G02X361243Y129685I0J5509D01*
G02X363816Y134347I5510J0D01*
G01X363861Y134374D01*
X363910Y134463D01*
Y134907D01*
X363861Y134996D01*
X363816Y135023D01*
G02Y144347I2937J4662D01*
G01X363861Y144374D01*
X363910Y144463D01*
Y144907D01*
X363861Y144996D01*
X363816Y145023D01*
G02Y154347I2937J4662D01*
G01X363861Y154374D01*
X363910Y154463D01*
G37*
G36*
G01X328910D02*
Y154907D01*
X328861Y154996D01*
X328816Y155023D01*
G02X326243Y159685I2937J4662D01*
G02X331752Y165194I5509J0D01*
G02X336414Y162621I0J-5510D01*
G01X336441Y162576D01*
X336530Y162527D01*
X336974D01*
X337063Y162576D01*
X337090Y162621D01*
G02X341752Y165194I4662J-2937D01*
G02X347261Y159685I0J-5509D01*
G02X344688Y155023I-5510J0D01*
G01X344643Y154996D01*
X344594Y154907D01*
Y154463D01*
X344643Y154374D01*
X344688Y154347D01*
G02Y145023I-2937J-4662D01*
G01X344643Y144996D01*
X344594Y144907D01*
Y144463D01*
X344643Y144374D01*
X344688Y144347D01*
G02Y135023I-2937J-4662D01*
G01X344643Y134996D01*
X344594Y134907D01*
Y134463D01*
X344643Y134374D01*
X344688Y134347D01*
G02X347261Y129685I-2937J-4662D01*
G02X341752Y124176I-5509J0D01*
G02X337090Y126749I0J5510D01*
G01X337063Y126794D01*
X336974Y126843D01*
X336530D01*
X336441Y126794D01*
X336414Y126749D01*
G02X331752Y124176I-4662J2937D01*
G02X326243Y129685I0J5509D01*
G02X328816Y134347I5510J0D01*
G01X328861Y134374D01*
X328910Y134463D01*
Y134907D01*
X328861Y134996D01*
X328816Y135023D01*
G02Y144347I2937J4662D01*
G01X328861Y144374D01*
X328910Y144463D01*
Y144907D01*
X328861Y144996D01*
X328816Y145023D01*
G02Y154347I2937J4662D01*
G01X328861Y154374D01*
X328910Y154463D01*
G37*
G36*
G01X293910D02*
Y154907D01*
X293861Y154996D01*
X293816Y155023D01*
G02X291243Y159685I2937J4662D01*
G02X296752Y165194I5509J0D01*
G02X301414Y162621I0J-5510D01*
G01X301441Y162576D01*
X301530Y162527D01*
X301974D01*
X302063Y162576D01*
X302090Y162621D01*
G02X306752Y165194I4662J-2937D01*
G02X312261Y159685I0J-5509D01*
G02X309688Y155023I-5510J0D01*
G01X309643Y154996D01*
X309594Y154907D01*
Y154463D01*
X309643Y154374D01*
X309688Y154347D01*
G02Y145023I-2937J-4662D01*
G01X309643Y144996D01*
X309594Y144907D01*
Y144463D01*
X309643Y144374D01*
X309688Y144347D01*
G02Y135023I-2937J-4662D01*
G01X309643Y134996D01*
X309594Y134907D01*
Y134463D01*
X309643Y134374D01*
X309688Y134347D01*
G02X312261Y129685I-2937J-4662D01*
G02X306752Y124176I-5509J0D01*
G02X302090Y126749I0J5510D01*
G01X302063Y126794D01*
X301974Y126843D01*
X301530D01*
X301441Y126794D01*
X301414Y126749D01*
G02X296752Y124176I-4662J2937D01*
G02X291243Y129685I0J5509D01*
G02X293816Y134347I5510J0D01*
G01X293861Y134374D01*
X293910Y134463D01*
Y134907D01*
X293861Y134996D01*
X293816Y135023D01*
G02Y144347I2937J4662D01*
G01X293861Y144374D01*
X293910Y144463D01*
Y144907D01*
X293861Y144996D01*
X293816Y145023D01*
G02Y154347I2937J4662D01*
G01X293861Y154374D01*
X293910Y154463D01*
G37*
G36*
G01X511811Y69432D02*
G02Y25056I0J-22188D01*
G01X425197D01*
G02Y69432I0J22188D01*
G01X511811D01*
G37*
G36*
G01X1030500Y564688D02*
G02Y520312I0J-22188D01*
G01X943886D01*
G02Y564688I0J22188D01*
G01X1030500D01*
G37*
G36*
G01X586166Y447572D02*
G02X589500Y450002I3334J-1072D01*
G02X593002Y446500I0J-3502D01*
G02X590942Y443309I-3501J0D01*
G03X590834Y443188I82J-182D01*
G02X587500Y440758I-3334J1072D01*
G02X583998Y444260I0J3502D01*
G02X586058Y447451I3501J0D01*
G03X586166Y447572I-82J182D01*
G37*
G36*
G01X182120Y501202D02*
G02X183537Y501502I1418J-3202D01*
G01X183539D01*
G02Y494498I0J-3502D01*
G01X183537D01*
G02X182120Y494798I1J3502D01*
G03X181958I-81J-182D01*
G02X180541Y494498I-1418J3202D01*
G01X180539D01*
G02Y501502I0J3502D01*
G01X180541D01*
G02X181958Y501202I-1J-3502D01*
G03X182120I81J182D01*
G37*
G36*
G01X230120D02*
G02X231537Y501502I1418J-3202D01*
G01X231539D01*
G02Y494498I0J-3502D01*
G01X231537D01*
G02X230120Y494798I1J3502D01*
G03X229958I-81J-182D01*
G02X228541Y494498I-1418J3202D01*
G01X228539D01*
G02Y501502I0J3502D01*
G01X228541D01*
G02X229958Y501202I-1J-3502D01*
G03X230120I81J182D01*
G37*
G36*
G01X278120D02*
G02X279537Y501502I1418J-3202D01*
G01X279539D01*
G02Y494498I0J-3502D01*
G01X279537D01*
G02X278120Y494798I1J3502D01*
G03X277958I-81J-182D01*
G02X276541Y494498I-1418J3202D01*
G01X276539D01*
G02Y501502I0J3502D01*
G01X276541D01*
G02X277958Y501202I-1J-3502D01*
G03X278120I81J182D01*
G37*
G36*
G01X339600D02*
G02X341017Y501502I1418J-3202D01*
G01X341019D01*
G02Y494498I0J-3502D01*
G01X341017D01*
G02X339600Y494798I1J3502D01*
G03X339438I-81J-182D01*
G02X338021Y494498I-1418J3202D01*
G01X338019D01*
G02Y501502I0J3502D01*
G01X338021D01*
G02X339438Y501202I-1J-3502D01*
G03X339600I81J182D01*
G37*
G36*
G01X387600D02*
G02X389017Y501502I1418J-3202D01*
G01X389019D01*
G02Y494498I0J-3502D01*
G01X389017D01*
G02X387600Y494798I1J3502D01*
G03X387438I-81J-182D01*
G02X386021Y494498I-1418J3202D01*
G01X386019D01*
G02Y501502I0J3502D01*
G01X386021D01*
G02X387438Y501202I-1J-3502D01*
G03X387600I81J182D01*
G37*
G36*
G01X435600D02*
G02X437017Y501502I1418J-3202D01*
G01X437019D01*
G02Y494498I0J-3502D01*
G01X437017D01*
G02X435600Y494798I1J3502D01*
G03X435438I-81J-182D01*
G02X434021Y494498I-1418J3202D01*
G01X434019D01*
G02Y501502I0J3502D01*
G01X434021D01*
G02X435438Y501202I-1J-3502D01*
G03X435600I81J182D01*
G37*
G36*
G01X497081D02*
G02X498498Y501502I1418J-3202D01*
G01X498500D01*
G02Y494498I0J-3502D01*
G01X498498D01*
G02X497081Y494798I1J3502D01*
G03X496919I-81J-182D01*
G02X495502Y494498I-1418J3202D01*
G01X495500D01*
G02Y501502I0J3502D01*
G01X495502D01*
G02X496919Y501202I-1J-3502D01*
G03X497081I81J182D01*
G37*
G36*
G01X545081D02*
G02X546498Y501502I1418J-3202D01*
G01X546500D01*
G02Y494498I0J-3502D01*
G01X546498D01*
G02X545081Y494798I1J3502D01*
G03X544919I-81J-182D01*
G02X543502Y494498I-1418J3202D01*
G01X543500D01*
G02Y501502I0J3502D01*
G01X543502D01*
G02X544919Y501202I-1J-3502D01*
G03X545081I81J182D01*
G37*
G36*
G01X593081D02*
G02X594498Y501502I1418J-3202D01*
G01X594500D01*
G02Y494498I0J-3502D01*
G01X594498D01*
G02X593081Y494798I1J3502D01*
G03X592919I-81J-182D01*
G02X591502Y494498I-1418J3202D01*
G01X591500D01*
G02Y501502I0J3502D01*
G01X591502D01*
G02X592919Y501202I-1J-3502D01*
G03X593081I81J182D01*
G37*
G36*
G01X654562D02*
G02X655979Y501502I1418J-3202D01*
G01X655981D01*
G02Y494498I0J-3502D01*
G01X655979D01*
G02X654562Y494798I1J3502D01*
G03X654400I-81J-182D01*
G02X652983Y494498I-1418J3202D01*
G01X652981D01*
G02Y501502I0J3502D01*
G01X652983D01*
G02X654400Y501202I-1J-3502D01*
G03X654562I81J182D01*
G37*
G36*
G01X702562D02*
G02X703979Y501502I1418J-3202D01*
G01X703981D01*
G02Y494498I0J-3502D01*
G01X703979D01*
G02X702562Y494798I1J3502D01*
G03X702400I-81J-182D01*
G02X700983Y494498I-1418J3202D01*
G01X700981D01*
G02Y501502I0J3502D01*
G01X700983D01*
G02X702400Y501202I-1J-3502D01*
G03X702562I81J182D01*
G37*
G36*
G01X750562D02*
G02X751979Y501502I1418J-3202D01*
G01X751981D01*
G02Y494498I0J-3502D01*
G01X751979D01*
G02X750562Y494798I1J3502D01*
G03X750400I-81J-182D01*
G02X748983Y494498I-1418J3202D01*
G01X748981D01*
G02Y501502I0J3502D01*
G01X748983D01*
G02X750400Y501202I-1J-3502D01*
G03X750562I81J182D01*
G37*
G36*
G01X182120Y521202D02*
G02X183537Y521502I1418J-3202D01*
G01X183539D01*
G02Y514498I0J-3502D01*
G01X183537D01*
G02X182120Y514798I1J3502D01*
G03X181958I-81J-182D01*
G02X180541Y514498I-1418J3202D01*
G01X180539D01*
G02Y521502I0J3502D01*
G01X180541D01*
G02X181958Y521202I-1J-3502D01*
G03X182120I81J182D01*
G37*
G36*
G01X230120D02*
G02X231537Y521502I1418J-3202D01*
G01X231539D01*
G02Y514498I0J-3502D01*
G01X231537D01*
G02X230120Y514798I1J3502D01*
G03X229958I-81J-182D01*
G02X228541Y514498I-1418J3202D01*
G01X228539D01*
G02Y521502I0J3502D01*
G01X228541D01*
G02X229958Y521202I-1J-3502D01*
G03X230120I81J182D01*
G37*
G36*
G01X278120D02*
G02X279537Y521502I1418J-3202D01*
G01X279539D01*
G02Y514498I0J-3502D01*
G01X279537D01*
G02X278120Y514798I1J3502D01*
G03X277958I-81J-182D01*
G02X276541Y514498I-1418J3202D01*
G01X276539D01*
G02Y521502I0J3502D01*
G01X276541D01*
G02X277958Y521202I-1J-3502D01*
G03X278120I81J182D01*
G37*
G36*
G01X339600D02*
G02X341017Y521502I1418J-3202D01*
G01X341019D01*
G02Y514498I0J-3502D01*
G01X341017D01*
G02X339600Y514798I1J3502D01*
G03X339438I-81J-182D01*
G02X338021Y514498I-1418J3202D01*
G01X338019D01*
G02Y521502I0J3502D01*
G01X338021D01*
G02X339438Y521202I-1J-3502D01*
G03X339600I81J182D01*
G37*
G36*
G01X387600D02*
G02X389017Y521502I1418J-3202D01*
G01X389019D01*
G02Y514498I0J-3502D01*
G01X389017D01*
G02X387600Y514798I1J3502D01*
G03X387438I-81J-182D01*
G02X386021Y514498I-1418J3202D01*
G01X386019D01*
G02Y521502I0J3502D01*
G01X386021D01*
G02X387438Y521202I-1J-3502D01*
G03X387600I81J182D01*
G37*
G36*
G01X435600D02*
G02X437017Y521502I1418J-3202D01*
G01X437019D01*
G02Y514498I0J-3502D01*
G01X437017D01*
G02X435600Y514798I1J3502D01*
G03X435438I-81J-182D01*
G02X434021Y514498I-1418J3202D01*
G01X434019D01*
G02Y521502I0J3502D01*
G01X434021D01*
G02X435438Y521202I-1J-3502D01*
G03X435600I81J182D01*
G37*
G36*
G01X497081D02*
G02X498498Y521502I1418J-3202D01*
G01X498500D01*
G02Y514498I0J-3502D01*
G01X498498D01*
G02X497081Y514798I1J3502D01*
G03X496919I-81J-182D01*
G02X495502Y514498I-1418J3202D01*
G01X495500D01*
G02Y521502I0J3502D01*
G01X495502D01*
G02X496919Y521202I-1J-3502D01*
G03X497081I81J182D01*
G37*
G36*
G01X545081D02*
G02X546498Y521502I1418J-3202D01*
G01X546500D01*
G02Y514498I0J-3502D01*
G01X546498D01*
G02X545081Y514798I1J3502D01*
G03X544919I-81J-182D01*
G02X543502Y514498I-1418J3202D01*
G01X543500D01*
G02Y521502I0J3502D01*
G01X543502D01*
G02X544919Y521202I-1J-3502D01*
G03X545081I81J182D01*
G37*
G36*
G01X593081D02*
G02X594498Y521502I1418J-3202D01*
G01X594500D01*
G02Y514498I0J-3502D01*
G01X594498D01*
G02X593081Y514798I1J3502D01*
G03X592919I-81J-182D01*
G02X591502Y514498I-1418J3202D01*
G01X591500D01*
G02Y521502I0J3502D01*
G01X591502D01*
G02X592919Y521202I-1J-3502D01*
G03X593081I81J182D01*
G37*
G36*
G01X654562D02*
G02X655979Y521502I1418J-3202D01*
G01X655981D01*
G02Y514498I0J-3502D01*
G01X655979D01*
G02X654562Y514798I1J3502D01*
G03X654400I-81J-182D01*
G02X652983Y514498I-1418J3202D01*
G01X652981D01*
G02Y521502I0J3502D01*
G01X652983D01*
G02X654400Y521202I-1J-3502D01*
G03X654562I81J182D01*
G37*
G36*
G01X702562D02*
G02X703979Y521502I1418J-3202D01*
G01X703981D01*
G02Y514498I0J-3502D01*
G01X703979D01*
G02X702562Y514798I1J3502D01*
G03X702400I-81J-182D01*
G02X700983Y514498I-1418J3202D01*
G01X700981D01*
G02Y521502I0J3502D01*
G01X700983D01*
G02X702400Y521202I-1J-3502D01*
G03X702562I81J182D01*
G37*
G36*
G01X750562D02*
G02X751979Y521502I1418J-3202D01*
G01X751981D01*
G02Y514498I0J-3502D01*
G01X751979D01*
G02X750562Y514798I1J3502D01*
G03X750400I-81J-182D01*
G02X748983Y514498I-1418J3202D01*
G01X748981D01*
G02Y521502I0J3502D01*
G01X748983D01*
G02X750400Y521202I-1J-3502D01*
G03X750562I81J182D01*
G37*
G36*
G01X746727Y26525D02*
G02X743658Y30000I433J3475D01*
G02X747160Y33502I3502J0D01*
G02X748264Y33324I2J-3502D01*
G03X748404Y33329I63J189D01*
G02X749760Y33602I1356J-3229D01*
G02X751084Y33342I0J-3501D01*
G03X751236I76J185D01*
G02X752560Y33602I1324J-3241D01*
G02X756062Y30100I0J-3502D01*
G02X753889Y26860I-3502J0D01*
G03X753767Y26703I76J-185D01*
G02X750300Y23698I-3467J498D01*
G02X746897Y26374I0J3502D01*
G03X746727Y26525I-194J-48D01*
G37*
G36*
G01X748516Y35271D02*
G02X747160Y34998I-1356J3229D01*
G02Y42002I0J3502D01*
G02X748264Y41824I2J-3502D01*
G03X748404Y41829I63J189D01*
G02X749760Y42102I1356J-3229D01*
G02X751084Y41842I0J-3501D01*
G03X751236I76J185D01*
G02X752560Y42102I1324J-3241D01*
G02Y35098I0J-3502D01*
G02X751236Y35358I0J3501D01*
G03X751084I-76J-185D01*
G02X749760Y35098I-1324J3241D01*
G02X748656Y35276I-2J3502D01*
G03X748516Y35271I-63J-189D01*
G37*
G36*
G01Y43771D02*
G02X747160Y43498I-1356J3229D01*
G02Y50502I0J3502D01*
G02X748264Y50324I2J-3502D01*
G03X748404Y50329I63J189D01*
G02X749760Y50602I1356J-3229D01*
G02X751084Y50342I0J-3501D01*
G03X751236I76J185D01*
G02X752560Y50602I1324J-3241D01*
G02Y43598I0J-3502D01*
G02X751236Y43858I0J3501D01*
G03X751084I-76J-185D01*
G02X749760Y43598I-1324J3241D01*
G02X748656Y43776I-2J3502D01*
G03X748516Y43771I-63J-189D01*
G37*
G36*
G01Y52271D02*
G02X747160Y51998I-1356J3229D01*
G02Y59002I0J3502D01*
G02X748264Y58824I2J-3502D01*
G03X748404Y58829I63J189D01*
G02X749760Y59102I1356J-3229D01*
G02X751084Y58842I0J-3501D01*
G03X751236I76J185D01*
G02X752560Y59102I1324J-3241D01*
G02Y52098I0J-3502D01*
G02X751236Y52358I0J3501D01*
G03X751084I-76J-185D01*
G02X749760Y52098I-1324J3241D01*
G02X748656Y52276I-2J3502D01*
G03X748516Y52271I-63J-189D01*
G37*
G36*
G01Y60771D02*
G02X747160Y60498I-1356J3229D01*
G02Y67502I0J3502D01*
G02X748264Y67324I2J-3502D01*
G03X748404Y67329I63J189D01*
G02X749760Y67602I1356J-3229D01*
G02X751084Y67342I0J-3501D01*
G03X751236I76J185D01*
G02X752560Y67602I1324J-3241D01*
G02Y60598I0J-3502D01*
G02X751236Y60858I0J3501D01*
G03X751084I-76J-185D01*
G02X749760Y60598I-1324J3241D01*
G02X748656Y60776I-2J3502D01*
G03X748516Y60771I-63J-189D01*
G37*
G36*
G01X1075308Y93847D02*
G02X1077200Y94402I1892J-2947D01*
G02Y87398I0J-3502D01*
G02X1075308Y87953I0J3502D01*
G03X1075092I-108J-168D01*
G02X1073200Y87398I-1892J2947D01*
G02Y94402I0J3502D01*
G02X1075092Y93847I0J-3502D01*
G03X1075308I108J168D01*
G37*
G36*
G01X1047918Y143467D02*
G02X1047854Y143900I1438J434D01*
G02X1049356Y142398I1502J0D01*
G02X1049059Y142428I2J1502D01*
G03X1048597Y141920I-79J-392D01*
G02X1048661Y141487I-1438J-434D01*
G02X1047159Y142989I-1502J0D01*
G02X1047456Y142959I-2J-1502D01*
G03X1047918Y143467I79J392D01*
G37*
G54D41*
X703740Y41000D03*
Y54118D03*
X690075Y39500D03*
X707000Y32000D03*
X694425Y29500D03*
X1070715Y146500D03*
X1057525Y138600D03*
X1193411Y328750D03*
X1193840Y471250D03*
G54D29*
X578500Y240000D03*
X666500D03*
X735981D03*
X428500D03*
X823981D03*
X779981D03*
X268000D03*
X312500D03*
X357000D03*
X472500D03*
X516500D03*
X622500D03*
X1061600Y359642D03*
X223819Y445025D03*
X538780D03*
X381299D03*
X1067730Y460352D03*
X1061600Y466242D03*
Y323742D03*
Y276242D03*
Y513742D03*
X1067866Y507629D03*
X1067707Y365442D03*
X1067701Y270442D03*
X1067679Y317942D03*
X1067531Y412942D03*
X473095Y340339D03*
X313571Y340552D03*
X447255Y340339D03*
X173265Y340552D03*
X545063Y340339D03*
X290720Y340338D03*
X430019Y444260D03*
X432019Y452025D03*
X696261Y445024D03*
X549500D03*
X1060984Y418742D03*
X1074316Y406925D03*
X1092000Y82500D03*
G54D43*
X1090500Y376500D03*
G54D36*
X165539Y539000D03*
X213539D03*
X261539D03*
X323019D03*
X371019D03*
X419019D03*
X480500D03*
X528500D03*
X576500D03*
X637981D03*
X685981D03*
X733981D03*
G54D39*
X1256024Y286929D03*
X1246024D03*
X1236024D03*
X812559Y119408D03*
X822559D03*
X832559D03*
X812559Y129408D03*
X822559D03*
X832559D03*
X822559Y139408D03*
X832559D03*
X812559Y149408D03*
X822559D03*
X832559D03*
G54D38*
X1011000Y98000D03*
X1171000Y90400D03*
X1151000D03*
G54D30*
X268000Y220315D03*
X312500D03*
X666500D03*
X823981D03*
X779981D03*
X735981D03*
X578500D03*
X622500D03*
X428500D03*
X516500D03*
X472500D03*
X357000D03*
G54D37*
X185224Y539000D03*
X233224D03*
X281224D03*
X342704D03*
X390704D03*
X438704D03*
X500185D03*
X548185D03*
X596185D03*
X657666D03*
X705666D03*
X753666D03*
G54D34*
X253819Y477204D03*
X411299D03*
X568780D03*
X726261D03*
G54D40*
X1226024Y286929D03*
G54D31*
X583780Y277204D03*
X426299D03*
X268819D03*
G54D35*
X193819Y477204D03*
X223819D03*
X351299D03*
X381299D03*
X508780D03*
X538780D03*
X666261D03*
X696261D03*
G54D33*
X249252Y129685D03*
X529252D03*
X665059Y149408D03*
G54D42*
X1226024Y174429D03*
Y399429D03*
G54D32*
X175000Y100500D03*
X964460Y16950D03*
%LPD*%
G75*
G36*
G01X246000Y279000D02*
X247194Y277806D01*
G03X247167Y277211I6625J-599D01*
G01Y277204D01*
G03X253819Y270552I6652J0D01*
G03X258511Y272489I0J6651D01*
G01X263000Y268000D01*
Y262000D01*
X261000Y260000D01*
X253100D01*
X252200Y260900D01*
Y266549D01*
X251545Y267204D01*
G03X247441Y271308I-4104J0D01*
G03X247014Y271286I-3J-4104D01*
G01X243814D01*
X242600Y272500D01*
Y277200D01*
X244400Y279000D01*
X246000D01*
G37*
G36*
G01X403480D02*
X404674Y277806D01*
G03X404647Y277211I6625J-599D01*
G01Y277204D01*
G03X411299Y270552I6652J0D01*
G03X415991Y272489I0J6651D01*
G01X420480Y268000D01*
Y262000D01*
X418480Y260000D01*
X410580D01*
X409680Y260900D01*
Y266549D01*
X409025Y267204D01*
G03X404921Y271308I-4104J0D01*
G03X404494Y271286I-3J-4104D01*
G01X401294D01*
X400080Y272500D01*
Y277200D01*
X401880Y279000D01*
X403480D01*
G37*
G54D10*
G01X35679Y269497D02*
X38780Y272598D01*
G01X35679Y275699D02*
X38780Y272598D01*
G01X35679Y276190D02*
X38780Y279291D01*
G01X35679Y282392D02*
X38780Y279291D01*
G01X35679Y289497D02*
X38780Y292598D01*
G01X35679Y295699D02*
X38780Y292598D01*
G01X35679Y296190D02*
X38780Y299291D01*
G01X35679Y302392D02*
X38780Y299291D01*
G01Y272598D02*
X41881Y275699D01*
G01X38780Y272598D02*
X41881Y269497D01*
G01X38780Y279291D02*
X41881Y282392D01*
G01X38780Y279291D02*
X41881Y276190D01*
G01X45679D02*
X48780Y279291D01*
G01D02*
X51881Y282392D01*
G01X45679D02*
X48780Y279291D01*
G01D02*
X51881Y276190D01*
G01X45679Y269497D02*
X48780Y272598D01*
G01D02*
X51881Y275699D01*
G01X45679D02*
X48780Y272598D01*
G01D02*
X51881Y269497D01*
G01X45679Y289497D02*
X48780Y292598D01*
G01D02*
X51881Y295699D01*
G01X45679D02*
X48780Y292598D01*
G01D02*
X51881Y289497D01*
G01X38780Y292598D02*
X41881Y295699D01*
G01X38780Y292598D02*
X41881Y289497D01*
G01X38780Y299291D02*
X41881Y302392D01*
G01X38780Y299291D02*
X41881Y296190D01*
G01X45679D02*
X48780Y299291D01*
G01D02*
X51881Y302392D01*
G01X45679D02*
X48780Y299291D01*
G01D02*
X51881Y296190D01*
X3005Y19808D03*
Y34808D03*
Y59808D03*
X7595Y128373D03*
X3005Y145238D03*
Y165238D03*
Y185238D03*
Y205238D03*
Y225238D03*
Y245238D03*
Y265238D03*
Y285238D03*
Y305238D03*
Y325238D03*
Y345238D03*
Y365238D03*
Y385238D03*
Y405238D03*
Y425238D03*
Y445238D03*
X3023Y524312D03*
Y549312D03*
X4540Y566003D03*
X34582Y3004D03*
X14811Y3732D03*
X12767Y72072D03*
X27271Y127298D03*
X19558Y454589D03*
X9913Y510026D03*
X20498Y575739D03*
X54582Y3004D03*
X63436Y353962D03*
X39549Y454916D03*
X40498Y575739D03*
X60498D03*
X94582Y3004D03*
X74582D03*
X80498Y575739D03*
X114582Y3004D03*
X108600Y258560D03*
X111600D03*
X108600Y261560D03*
X111600D03*
X108600Y255560D03*
X111600D03*
X123000Y414500D03*
X119500D03*
Y411500D03*
X123000D03*
X119500Y408500D03*
X123000D03*
X119500Y417500D03*
X123000D03*
X119500Y420500D03*
X123000D03*
X115700Y420600D03*
Y417600D03*
Y408600D03*
Y411600D03*
Y414600D03*
X123000Y426600D03*
X119500D03*
X123000Y423600D03*
X119500D03*
X115700Y423700D03*
Y426700D03*
X100498Y575739D03*
X120498D03*
X154582Y3004D03*
X134582D03*
X150634Y219063D03*
X155034Y228063D03*
Y224563D03*
X152334Y223063D03*
Y226563D03*
Y230063D03*
X155034Y231563D03*
X140498Y575739D03*
X174582Y3004D03*
X182260Y197050D03*
X179460D03*
X176560D03*
X174660Y205850D03*
Y202650D03*
X167660Y213050D03*
X164760D03*
X167660Y209850D03*
X164760D03*
X183900Y216830D03*
X165840Y247805D03*
X169840D03*
X157000Y414500D03*
X160500D03*
Y417500D03*
X157000D03*
X160500Y420500D03*
X157000D03*
X160500Y411500D03*
X157000D03*
X160500Y408500D03*
X157000D03*
X164000Y414600D03*
Y417600D03*
Y420600D03*
Y411600D03*
Y408600D03*
X160300Y423600D03*
X156800D03*
X160300Y426600D03*
X156800D03*
X163800Y426700D03*
Y423700D03*
X168939Y498000D03*
X171939D03*
Y518000D03*
X168939D03*
X214582Y3004D03*
X194582D03*
X194160Y205200D03*
Y208200D03*
X200160Y205200D03*
Y208200D03*
X197160Y205200D03*
Y208200D03*
X185260Y205350D03*
Y208350D03*
X203575Y297500D03*
X212925Y315500D03*
X234582Y3004D03*
X230425Y313605D03*
X221425Y313000D03*
X216939Y498000D03*
X219939D03*
Y518000D03*
X216939D03*
X254582Y3004D03*
X264939Y498000D03*
X267939D03*
Y518000D03*
X264939D03*
X294582Y3004D03*
X274582D03*
X283000Y203500D03*
Y198500D03*
Y196000D03*
Y206000D03*
X285219Y279078D03*
X281219D03*
X277219D03*
X285219Y275078D03*
X281219D03*
X277219D03*
X285219Y271078D03*
X281219D03*
X277219D03*
Y283078D03*
X281219D03*
X285219D03*
X314582Y3004D03*
X326000Y203500D03*
Y198500D03*
Y196000D03*
Y206000D03*
X304500Y203500D03*
Y198500D03*
Y196000D03*
Y206000D03*
X326419Y498000D03*
X329419D03*
Y518000D03*
X326419D03*
X354582Y3004D03*
X334582D03*
X347500Y203500D03*
Y198500D03*
Y196000D03*
Y206000D03*
X374582Y3004D03*
X390500Y203500D03*
Y198500D03*
Y196000D03*
Y206000D03*
X369000Y203500D03*
Y198500D03*
Y196000D03*
Y206000D03*
X382963Y316400D03*
Y313750D03*
X374419Y498000D03*
X377419D03*
Y518000D03*
X374419D03*
X414582Y3004D03*
X394582D03*
X412000Y203500D03*
Y198500D03*
Y196000D03*
Y206000D03*
X434582Y3004D03*
X442499Y279186D03*
X438499D03*
X434499D03*
X442499Y275186D03*
X438499D03*
X434499D03*
X442499Y271186D03*
X438499D03*
X434499D03*
Y283186D03*
X438499D03*
X442499D03*
X422419Y498000D03*
X425419D03*
Y518000D03*
X422419D03*
X474582Y3004D03*
X454582D03*
X494582D03*
X483900Y498000D03*
X486900D03*
Y518000D03*
X483900D03*
X534582Y3004D03*
X514582D03*
X518575Y295500D03*
X539619Y316400D03*
Y313400D03*
X531900Y498000D03*
X534900D03*
Y518000D03*
X531900D03*
X554582Y3004D03*
X562000Y442000D03*
X564500D03*
X594582Y3004D03*
X574582D03*
X590500Y203000D03*
Y198000D03*
Y195500D03*
Y205500D03*
X582900Y518000D03*
Y498000D03*
X579900D03*
Y518000D03*
X614582Y3004D03*
X612000Y203000D03*
Y198000D03*
Y195500D03*
Y205500D03*
X654582Y3004D03*
X634582D03*
X640900Y42300D03*
X660200Y56800D03*
X655300D03*
X652300D03*
X638200Y44000D03*
Y46500D03*
X641100Y48100D03*
X655000Y203000D03*
Y198000D03*
Y195500D03*
Y205500D03*
X633500Y203000D03*
Y198000D03*
Y195500D03*
Y205500D03*
X644381Y518000D03*
Y498000D03*
X641381D03*
Y518000D03*
X674582Y3004D03*
X684525Y32500D03*
Y36500D03*
X683600Y56800D03*
X679000D03*
X676000D03*
X686500D03*
X671100D03*
X668100D03*
X663200D03*
X676500Y195500D03*
Y198000D03*
Y203000D03*
Y205500D03*
X676075Y299600D03*
X680400Y310500D03*
X714582Y3004D03*
X694582D03*
X699500Y34500D03*
X696900Y53300D03*
X694200D03*
X691400D03*
X689900Y56600D03*
X693000D03*
X696100Y56700D03*
X706000Y61975D03*
X697990Y195500D03*
Y198000D03*
Y203000D03*
Y205500D03*
X716100Y255987D03*
X700040Y258960D03*
X694406Y295500D03*
X697100Y313400D03*
X704400Y358600D03*
X697900Y352500D03*
X707750Y358750D03*
X692381Y518000D03*
Y498000D03*
X689381D03*
Y518000D03*
X734582Y3004D03*
X719490Y195500D03*
Y198000D03*
Y203000D03*
Y205500D03*
X724000Y294500D03*
X735075Y326000D03*
Y336000D03*
X731925D03*
X732000Y326000D03*
X740381Y518000D03*
Y498000D03*
X737381D03*
Y518000D03*
X774582Y3004D03*
X754582D03*
X761560Y38500D03*
X758760D03*
X756160D03*
X761560Y30000D03*
X758760D03*
X756160D03*
X758900Y27400D03*
X761560Y55500D03*
X758760D03*
X756160D03*
X761560Y47000D03*
X758760D03*
X756160D03*
X761560Y64000D03*
X758760D03*
X756160D03*
X754000Y353500D03*
Y356957D03*
X748075Y366500D03*
X794582Y3004D03*
X779100Y326820D03*
X798400Y323900D03*
X781500Y362700D03*
X802975Y362000D03*
X805323Y408150D03*
Y405150D03*
X799323D03*
Y408150D03*
X802323Y405150D03*
Y408150D03*
X796600Y408097D03*
Y405097D03*
X802323Y416916D03*
X799323D03*
X805323D03*
X802323Y413916D03*
X799323D03*
X805323D03*
Y411150D03*
X799323D03*
X802323D03*
X796600Y411097D03*
Y413863D03*
Y416863D03*
X799655Y474684D03*
Y480503D03*
Y477684D03*
X802655Y474684D03*
Y480503D03*
Y477684D03*
X805655Y474684D03*
Y480503D03*
Y477684D03*
X802655Y483503D03*
X805709Y486332D03*
X805655Y483503D03*
X796655Y474684D03*
Y480503D03*
Y477684D03*
X796709Y486332D03*
X796655Y483503D03*
X799709Y486332D03*
X799655Y483503D03*
X802709Y486332D03*
X834582Y3004D03*
X814582D03*
X836500Y302500D03*
X808425Y334000D03*
X829500Y354925D03*
X827000Y360475D03*
X808425Y344000D03*
X811323Y405150D03*
Y408150D03*
X808323D03*
Y405150D03*
Y416916D03*
X811323D03*
X808323Y413916D03*
X811323D03*
Y411150D03*
X808323D03*
X817153Y408096D03*
Y405096D03*
X814323Y405150D03*
Y408150D03*
Y416916D03*
X817153Y416862D03*
X814323Y413916D03*
X817153Y413862D03*
Y411096D03*
X814323Y411150D03*
X817709Y486332D03*
X817655Y483503D03*
X808655Y474684D03*
Y480503D03*
Y477684D03*
X811655Y474684D03*
Y480503D03*
Y477684D03*
X814655D03*
Y480503D03*
Y474684D03*
X808709Y486332D03*
X808655Y483503D03*
X811709Y486332D03*
X811655Y483503D03*
X814655D03*
X814709Y486332D03*
X817655Y474684D03*
Y480503D03*
Y477684D03*
X854582Y3004D03*
X863600Y208900D03*
X850750Y250750D03*
X853000Y303500D03*
X861600Y304600D03*
X864500Y358500D03*
X849000Y399000D03*
X850390Y385878D03*
X847390D03*
X859253D03*
X856253D03*
X865542Y385771D03*
X859342Y413916D03*
X856342D03*
X865342D03*
X862342D03*
Y411150D03*
X865342D03*
X856342D03*
X859342D03*
X853619Y411097D03*
Y413863D03*
Y416863D03*
X862342Y408150D03*
Y405150D03*
X865342Y408150D03*
Y405150D03*
X856342D03*
Y408150D03*
X859342Y405150D03*
Y408150D03*
X853619Y408097D03*
Y405097D03*
X859342Y416916D03*
X856342D03*
X865342D03*
X862342D03*
X856257Y474684D03*
Y480503D03*
Y477684D03*
X859257Y474684D03*
Y480503D03*
Y477684D03*
X862257Y474684D03*
Y480503D03*
Y477684D03*
X859257Y483503D03*
X862311Y486332D03*
X862257Y483503D03*
X853257Y474684D03*
Y480503D03*
Y477684D03*
X853311Y486332D03*
X853257Y483503D03*
X856311Y486332D03*
X856257Y483503D03*
X859311Y486332D03*
X865311D03*
X865257Y483503D03*
Y474684D03*
Y480503D03*
Y477684D03*
X854082Y505410D03*
X848263D03*
X851082D03*
X854082Y508410D03*
X848263D03*
X851082D03*
X854082Y511410D03*
X848263D03*
X851082D03*
X854082Y514410D03*
X848263D03*
X851082D03*
X845263Y508410D03*
X842434Y511464D03*
X845263Y511410D03*
X842434Y514464D03*
X845263Y514410D03*
X854082Y502410D03*
X848263D03*
X851082D03*
X842434Y502464D03*
X845263Y502410D03*
X842434Y505464D03*
X845263Y505410D03*
X842434Y508464D03*
Y523464D03*
X845263Y523410D03*
X854082Y517410D03*
X848263D03*
X851082D03*
Y520410D03*
X848263D03*
X854082D03*
X842434Y517464D03*
X845263Y517410D03*
Y520410D03*
X842434Y520464D03*
X854082Y523410D03*
X848263D03*
X851082D03*
X894582Y3004D03*
X874582D03*
X868000Y271500D03*
X867000Y291260D03*
X888000Y283475D03*
X869000Y360500D03*
X893091Y385771D03*
X874405D03*
X877405D03*
X868542D03*
X884228D03*
X887228D03*
X868342Y416916D03*
X871342D03*
X868342Y413916D03*
X871342D03*
Y411150D03*
X868342D03*
X874172Y408096D03*
Y405096D03*
Y416862D03*
Y413862D03*
Y411096D03*
X871342Y405150D03*
Y408150D03*
X868342Y405150D03*
Y408150D03*
X868311Y486332D03*
X868257Y483503D03*
Y477684D03*
Y480503D03*
Y474684D03*
X871311Y486332D03*
X874311D03*
X874257Y477684D03*
Y480503D03*
Y474684D03*
X871257Y483503D03*
Y474684D03*
Y480503D03*
Y477684D03*
X874257Y483503D03*
X914582Y3004D03*
X903500Y327975D03*
X910992Y361075D03*
X896091Y385771D03*
X912525Y385877D03*
X906662D03*
X903662D03*
X922454Y385771D03*
X915525Y385877D03*
X911776Y507184D03*
Y510184D03*
Y501184D03*
Y504184D03*
X923595Y498461D03*
X920595D03*
X920542Y504184D03*
X923542D03*
X920542Y501184D03*
X923542D03*
Y510184D03*
X920542D03*
X923542Y507184D03*
X920542D03*
Y513184D03*
X923542D03*
X911829Y498461D03*
X914829D03*
X917595D03*
X917542Y504184D03*
Y501184D03*
Y510184D03*
Y507184D03*
Y513184D03*
X914776D03*
Y507184D03*
Y510184D03*
Y501184D03*
Y504184D03*
X911776Y513184D03*
X920542Y516184D03*
X923542D03*
X917542D03*
X914776D03*
X911776D03*
X917596Y519014D03*
X914830D03*
X911830D03*
X923596D03*
X920596D03*
X934582Y3004D03*
X940575Y304000D03*
X935516Y361075D03*
X933196Y353360D03*
X925454Y385771D03*
X944247Y385877D03*
X941247D03*
X931317Y385771D03*
X934317D03*
X950110Y385877D03*
X953110D03*
X940498Y575739D03*
X974582Y3004D03*
X954582D03*
X960498Y575739D03*
X980498D03*
X994582Y3004D03*
X1000498Y575739D03*
X1034582Y3004D03*
X1014582D03*
X1022575Y100925D03*
Y115500D03*
X1043936Y145745D03*
X1022168Y155877D03*
Y161783D03*
X1017909Y151424D03*
X1017837Y154280D03*
X1039016Y183027D03*
X1039538Y179208D03*
X1022000Y171200D03*
X1019700Y166600D03*
X1020498Y575739D03*
X1040498D03*
X1054582Y3004D03*
X1073154Y140800D03*
X1062500Y191500D03*
X1058000D03*
X1053830Y191670D03*
X1060000Y249000D03*
X1063000D03*
X1066000D03*
Y246000D03*
X1063000D03*
X1060000D03*
X1066000Y243000D03*
X1063000D03*
X1060000D03*
X1069000Y246000D03*
Y243000D03*
X1072000Y246000D03*
Y243000D03*
X1060000Y252000D03*
X1063000D03*
X1066000D03*
Y258000D03*
X1063000D03*
X1060000D03*
X1066000Y255000D03*
X1063000D03*
X1060000D03*
X1069000Y258000D03*
Y255000D03*
X1072000Y258000D03*
Y255000D03*
X1060000Y296500D03*
X1063000D03*
X1066000D03*
Y293500D03*
X1063000D03*
X1060000D03*
X1069000D03*
X1060000Y299500D03*
X1063000D03*
X1066000D03*
Y305500D03*
X1063000D03*
X1060000D03*
X1066000Y302500D03*
X1063000D03*
X1060000D03*
X1069000Y305500D03*
Y302500D03*
X1066000Y290500D03*
X1063000D03*
X1060000D03*
X1069000D03*
X1072000Y293500D03*
Y305500D03*
Y302500D03*
Y290500D03*
X1066000Y338000D03*
X1063000D03*
X1060000D03*
X1069000D03*
X1072000D03*
X1060000Y344000D03*
X1063000D03*
X1066000D03*
X1060000Y347000D03*
X1063000D03*
X1066000D03*
Y341000D03*
X1063000D03*
X1060000D03*
X1066000Y353000D03*
X1063000D03*
X1060000D03*
X1066000Y350000D03*
X1063000D03*
X1060000D03*
X1069000Y353000D03*
Y350000D03*
Y341000D03*
X1072000Y353000D03*
Y350000D03*
Y341000D03*
X1066000Y397500D03*
X1063000D03*
X1060000D03*
X1069000D03*
X1060000Y391500D03*
X1063000D03*
X1066000D03*
X1060000Y394500D03*
X1063000D03*
X1066000D03*
Y388500D03*
X1063000D03*
X1060000D03*
X1066000Y385500D03*
X1063000D03*
X1060000D03*
X1069000Y388500D03*
Y385500D03*
X1072000Y397500D03*
Y388500D03*
Y385500D03*
X1066000Y400500D03*
X1063000D03*
X1060000D03*
X1069000D03*
X1072000D03*
X1066000Y433000D03*
X1063000D03*
X1060000D03*
X1069000D03*
X1060000Y439000D03*
X1063000D03*
X1066000D03*
X1060000Y442000D03*
X1063000D03*
X1066000D03*
Y436000D03*
X1063000D03*
X1060000D03*
X1069000D03*
X1072000Y433000D03*
Y436000D03*
X1066000Y448000D03*
X1063000D03*
X1060000D03*
X1066000Y445000D03*
X1063000D03*
X1060000D03*
X1069000Y448000D03*
Y445000D03*
X1072000Y448000D03*
Y445000D03*
X1069000Y480500D03*
Y483500D03*
X1060000Y480500D03*
X1063000D03*
X1066000D03*
X1060000Y483500D03*
X1063000D03*
X1066000D03*
Y486500D03*
X1063000D03*
X1060000D03*
X1072000Y480500D03*
Y483500D03*
X1069000Y492500D03*
Y495500D03*
X1060000Y492500D03*
X1063000D03*
X1066000D03*
X1060000Y495500D03*
X1063000D03*
X1066000D03*
Y489500D03*
X1063000D03*
X1060000D03*
X1072000Y492500D03*
Y495500D03*
X1066500Y538000D03*
Y541000D03*
X1069500D03*
X1066500Y544000D03*
X1069500D03*
Y538000D03*
X1060498Y575739D03*
X1069500Y547000D03*
Y550000D03*
X1066500Y547000D03*
Y550000D03*
Y553000D03*
X1069500D03*
X1094582Y3004D03*
X1074582D03*
X1097100Y35582D03*
Y38582D03*
X1099600D03*
Y35582D03*
X1102100D03*
Y38582D03*
X1096961Y18126D03*
Y21126D03*
X1099461D03*
Y18126D03*
X1101961D03*
Y21126D03*
X1097101Y53737D03*
Y56737D03*
X1099601D03*
Y53737D03*
X1102101D03*
Y56737D03*
X1091000Y99500D03*
X1095100D03*
X1087000Y100000D03*
X1073154Y137800D03*
X1092000Y159500D03*
X1094500Y143144D03*
X1094024Y179500D03*
X1101903Y285019D03*
X1101796Y331894D03*
X1086500Y356000D03*
Y403500D03*
X1080498Y575739D03*
X1100498D03*
X1114582Y3004D03*
X1125170Y35582D03*
Y38582D03*
X1127670D03*
Y35582D03*
X1130170D03*
Y38582D03*
X1104600Y35582D03*
Y38582D03*
X1107100Y35582D03*
Y38582D03*
X1104461Y18126D03*
Y21126D03*
X1106961Y18126D03*
Y21126D03*
X1130031D03*
Y18126D03*
X1127531D03*
Y21126D03*
X1125031D03*
Y18126D03*
X1104601Y53737D03*
Y56737D03*
X1107101Y53737D03*
Y56737D03*
X1113000Y101240D03*
X1119500Y86000D03*
Y83000D03*
X1126075Y135973D03*
X1115425Y138925D03*
X1108000Y172000D03*
X1118774Y284699D03*
X1112902D03*
X1110019Y284806D03*
X1104786Y284912D03*
X1121657Y284592D03*
X1118667Y331574D03*
X1112795D03*
X1109912Y331681D03*
X1104679Y331787D03*
X1121550Y331467D03*
X1104009Y427245D03*
X1120880Y426925D03*
X1115008D03*
X1112125Y427032D03*
X1106892Y427138D03*
X1123763Y426818D03*
X1103800Y474339D03*
X1106683Y474232D03*
X1111916Y474126D03*
X1114799Y474019D03*
X1120671D03*
X1123554Y473912D03*
X1111452Y544000D03*
Y541000D03*
X1114452Y544000D03*
Y541000D03*
Y538000D03*
X1111452D03*
X1120669Y544000D03*
Y541000D03*
X1123669Y544000D03*
Y541000D03*
Y538000D03*
X1120669D03*
X1120498Y575739D03*
X1114452Y553000D03*
X1111452D03*
X1114452Y550000D03*
X1111452D03*
X1114452Y547000D03*
X1111452D03*
X1123669Y553000D03*
X1120669D03*
X1123669Y550000D03*
X1120669D03*
X1123669Y547000D03*
X1120669D03*
X1154582Y3004D03*
X1134582D03*
X1132670Y35582D03*
X1135170D03*
Y38582D03*
X1132670D03*
X1135031Y21126D03*
Y18126D03*
X1132531Y21126D03*
Y18126D03*
X1132950Y82867D03*
Y85867D03*
X1135450D03*
Y82867D03*
X1137950D03*
X1140450D03*
X1142950D03*
Y85867D03*
X1140450D03*
X1137950D03*
X1138203Y266860D03*
Y260860D03*
Y263860D03*
X1135203Y260860D03*
Y263860D03*
Y266860D03*
X1138203Y257860D03*
Y254860D03*
X1135203Y257860D03*
Y254860D03*
X1159710Y306037D03*
X1156710D03*
X1159710Y303037D03*
X1156710D03*
X1159710Y300037D03*
X1156710D03*
X1159710Y297037D03*
X1156710D03*
Y294037D03*
X1159710D03*
Y309037D03*
X1156710D03*
X1135403Y302360D03*
Y305360D03*
X1138403Y302360D03*
Y305360D03*
X1135403Y308360D03*
X1138403D03*
X1159710Y312037D03*
X1156710D03*
X1159710Y321037D03*
X1156710D03*
X1159710Y318037D03*
X1156710D03*
X1159710Y315037D03*
X1156710D03*
X1135403Y314360D03*
Y311360D03*
X1138403D03*
Y314360D03*
Y361979D03*
X1135403D03*
X1138403Y358979D03*
X1135403D03*
X1138403Y355979D03*
X1135403D03*
X1138403Y352979D03*
X1135403D03*
X1138403Y349979D03*
X1135403D03*
X1135190Y396965D03*
X1138190D03*
X1135190Y399965D03*
X1138190D03*
X1135190Y402965D03*
Y405965D03*
Y408965D03*
X1138190Y402965D03*
Y405965D03*
Y408965D03*
X1159799Y448537D03*
X1156799D03*
X1159799Y445537D03*
X1156799D03*
X1159799Y442537D03*
X1156799D03*
X1159799Y439537D03*
X1156799D03*
Y436537D03*
X1159799D03*
Y454537D03*
X1156799D03*
X1159799Y451537D03*
X1156799D03*
X1135404Y457228D03*
Y454228D03*
Y451228D03*
Y445228D03*
Y448228D03*
X1138404Y454228D03*
Y451228D03*
Y445228D03*
Y448228D03*
Y457228D03*
X1159799Y457537D03*
X1156799D03*
X1159799Y463537D03*
X1156799D03*
X1159799Y460537D03*
X1156799D03*
X1135622Y485732D03*
Y470732D03*
Y467732D03*
Y479732D03*
Y476732D03*
Y473732D03*
Y482732D03*
X1138622D03*
Y473732D03*
Y476732D03*
Y479732D03*
Y470732D03*
Y485732D03*
Y467732D03*
X1140498Y575739D03*
X1160498D03*
X1174582Y3004D03*
X1183321Y123652D03*
X1185821D03*
X1188321D03*
Y120652D03*
X1185821D03*
X1183321D03*
X1180821D03*
Y123652D03*
X1178321D03*
Y120652D03*
X1177475Y111500D03*
X1179500Y105500D03*
X1162710Y306037D03*
Y303037D03*
Y300037D03*
Y297037D03*
Y294037D03*
Y309037D03*
X1179411Y334250D03*
Y337750D03*
X1162710Y312037D03*
Y321037D03*
Y318037D03*
Y315037D03*
X1180986Y349234D03*
X1177836D03*
X1162799Y448537D03*
Y445537D03*
Y442537D03*
Y439537D03*
Y436537D03*
Y454537D03*
Y451537D03*
Y457537D03*
Y463537D03*
Y460537D03*
X1180498Y575739D03*
X1214582Y3004D03*
X1194582D03*
X1203887Y306894D03*
X1200887D03*
X1197887D03*
X1203887Y303894D03*
X1200887D03*
X1197887D03*
X1203887Y300894D03*
X1200887D03*
X1197887D03*
X1203887Y297894D03*
X1200887D03*
X1197887D03*
X1203887Y294894D03*
X1200887D03*
X1197887D03*
Y321894D03*
X1200887D03*
X1203887D03*
Y318894D03*
X1200887D03*
X1197887D03*
X1203887Y315894D03*
X1200887D03*
X1197887D03*
X1203887Y312894D03*
X1200887D03*
X1197887D03*
X1203887Y309894D03*
X1200887D03*
X1197887D03*
X1197976Y437394D03*
X1200976D03*
X1203976D03*
X1197976Y440394D03*
X1200976D03*
X1203976D03*
X1197976Y443394D03*
X1200976D03*
X1203976D03*
X1197976Y446394D03*
X1200976D03*
X1203976D03*
X1197976Y449394D03*
X1200976D03*
X1203976D03*
X1197976Y452394D03*
X1200976D03*
X1203976D03*
X1197976Y455394D03*
X1200976D03*
X1203976D03*
X1197976Y464394D03*
X1200976D03*
X1203976D03*
X1197976Y458394D03*
X1200976D03*
X1203976D03*
X1197976Y461394D03*
X1200976D03*
X1203976D03*
X1200498Y575739D03*
X1220498D03*
X1234582Y3004D03*
X1240498Y575739D03*
X1277657Y4128D03*
X1254582Y3004D03*
X1260498Y575739D03*
X1279438Y573806D03*
X1286766Y12634D03*
X1288331Y30962D03*
Y70962D03*
Y50962D03*
Y90962D03*
Y130962D03*
Y110962D03*
Y150962D03*
Y190962D03*
Y170962D03*
Y210962D03*
Y230962D03*
Y270962D03*
Y250962D03*
Y290962D03*
Y330962D03*
Y310962D03*
Y350962D03*
Y390962D03*
Y370962D03*
Y410962D03*
Y450962D03*
Y430962D03*
Y470962D03*
Y510962D03*
Y490962D03*
Y530962D03*
X1287616Y563889D03*
X1288331Y550962D03*
G54D11*
X38780Y272598D03*
Y279291D03*
Y292598D03*
Y299291D03*
X48780Y272598D03*
Y279291D03*
Y292598D03*
Y299291D03*
G54D20*
X860237Y47244D03*
G54D21*
X1240158Y57480D03*
Y521260D03*
G54D12*
X48780Y319724D03*
G54D22*
X1161000Y90400D03*
G54D13*
X165350Y220098D03*
X162850D03*
Y227185D03*
Y230728D03*
X165350Y223642D03*
Y227185D03*
Y230728D03*
X162850Y223642D03*
G54D23*
G01X1022168Y155877D02*
Y157150D01*
X1023168Y158150D01*
X1025490D01*
X1028150Y160810D01*
Y162349D01*
X1028590Y162789D01*
Y163150D01*
G01X1022168Y161783D02*
Y160770D01*
X1023288Y159650D01*
X1024868D01*
X1026650Y161432D01*
Y163090D01*
X1026590Y163150D01*
G01X1029310Y154000D02*
X1028750D01*
X1026760Y152010D01*
X1018495D01*
X1017909Y151424D01*
G01X1027895Y155414D02*
Y155267D01*
X1026138Y153510D01*
X1018607D01*
X1017837Y154280D01*
G54D14*
X165539Y539000D03*
X213539D03*
X261539D03*
X323019D03*
X371019D03*
X419019D03*
X480500D03*
X528500D03*
X576500D03*
X637981D03*
X685981D03*
X733981D03*
G54D24*
G01X165840Y247805D02*
Y251260D01*
X152250Y264850D01*
Y286449D01*
X192301Y326500D01*
X613500D01*
X653500Y366500D01*
X748075D01*
G01X169840Y247805D02*
X165840D01*
G01X724000Y294500D02*
X708097Y278597D01*
Y263990D01*
X716100Y255987D01*
G01X748075Y366500D02*
X798475D01*
X802975Y362000D01*
G01D02*
X805575Y359400D01*
X825925D01*
X827000Y360475D01*
G01D02*
X829500Y357975D01*
Y354925D01*
G01X1028590Y163150D02*
Y195980D01*
X1047280Y214670D01*
X1152830D01*
X1174940Y236780D01*
Y333361D01*
X1176559Y334980D01*
X1178681D01*
X1179411Y334250D01*
G01X1026590Y163150D02*
Y196809D01*
X1046451Y216670D01*
X1152001D01*
X1172940Y237609D01*
Y334190D01*
X1175730Y336980D01*
X1178641D01*
X1179411Y337750D01*
G01X1180986Y349234D02*
X1180430Y348678D01*
Y345500D01*
X1185680Y340250D01*
Y238320D01*
X1155990Y208630D01*
X1049960D01*
X1033700Y192370D01*
Y158390D01*
X1029310Y154000D01*
G01X1177836Y349234D02*
X1178430Y348640D01*
Y344671D01*
X1183680Y339421D01*
Y239149D01*
X1155161Y210630D01*
X1049131D01*
X1031700Y193199D01*
Y159219D01*
X1027895Y155414D01*
G01X1108000Y172000D02*
X1105500D01*
X1104000Y173500D01*
Y176500D01*
X1101000Y179500D01*
X1094024D01*
G54D15*
X268000Y240000D03*
X312500D03*
X357000D03*
X428500D03*
X472500D03*
X516500D03*
X578500D03*
X622500D03*
X666500D03*
X735981D03*
X779981D03*
X823981D03*
G54D25*
G01X162651Y536112D02*
X165539Y539000D01*
G01D02*
X168427Y541888D01*
G01X162651D02*
X165539Y539000D01*
G01D02*
X168427Y536112D01*
G01X210651D02*
X213539Y539000D01*
G01D02*
X216427Y541888D01*
G01X210651D02*
X213539Y539000D01*
G01D02*
X216427Y536112D01*
G01X265182Y237182D02*
X268000Y240000D01*
G01D02*
X270818Y242818D01*
G01X265182D02*
X268000Y240000D01*
G01D02*
X270818Y237182D01*
G01X258651Y536112D02*
X261539Y539000D01*
G01D02*
X264427Y541888D01*
G01X258651D02*
X261539Y539000D01*
G01D02*
X264427Y536112D01*
G01X309682Y237182D02*
X312500Y240000D01*
G01D02*
X315318Y242818D01*
G01X309682D02*
X312500Y240000D01*
G01D02*
X315318Y237182D01*
G01X320131Y536112D02*
X323019Y539000D01*
G01D02*
X325907Y541888D01*
G01X320131D02*
X323019Y539000D01*
G01D02*
X325907Y536112D01*
G01X354182Y237182D02*
X357000Y240000D01*
G01D02*
X359818Y242818D01*
G01X354182D02*
X357000Y240000D01*
G01D02*
X359818Y237182D01*
G01X368131Y536112D02*
X371019Y539000D01*
G01D02*
X373907Y541888D01*
G01X368131D02*
X371019Y539000D01*
G01D02*
X373907Y536112D01*
G01X416131D02*
X419019Y539000D01*
G01D02*
X421907Y541888D01*
G01X416131D02*
X419019Y539000D01*
G01D02*
X421907Y536112D01*
G01X425682Y237182D02*
X428500Y240000D01*
G01D02*
X431318Y242818D01*
G01X425682D02*
X428500Y240000D01*
G01D02*
X431318Y237182D01*
G01X469682D02*
X472500Y240000D01*
G01D02*
X475318Y242818D01*
G01X469682D02*
X472500Y240000D01*
G01D02*
X475318Y237182D01*
G01X477612Y536112D02*
X480500Y539000D01*
G01D02*
X483388Y541888D01*
G01X477612D02*
X480500Y539000D01*
G01D02*
X483388Y536112D01*
G01X513682Y237182D02*
X516500Y240000D01*
G01D02*
X519318Y242818D01*
G01X513682D02*
X516500Y240000D01*
G01D02*
X519318Y237182D01*
G01X525612Y536112D02*
X528500Y539000D01*
G01D02*
X531388Y541888D01*
G01X525612D02*
X528500Y539000D01*
G01D02*
X531388Y536112D01*
G01X575682Y237182D02*
X578500Y240000D01*
G01D02*
X581318Y242818D01*
G01X575682D02*
X578500Y240000D01*
G01D02*
X581318Y237182D01*
G01X573612Y536112D02*
X576500Y539000D01*
G01D02*
X579388Y541888D01*
G01X573612D02*
X576500Y539000D01*
G01D02*
X579388Y536112D01*
G01X619682Y237182D02*
X622500Y240000D01*
G01D02*
X625318Y242818D01*
G01X619682D02*
X622500Y240000D01*
G01D02*
X625318Y237182D01*
G01X635093Y536112D02*
X637981Y539000D01*
G01D02*
X640869Y541888D01*
G01X635093D02*
X637981Y539000D01*
G01D02*
X640869Y536112D01*
G01X663682Y237182D02*
X666500Y240000D01*
G01D02*
X669318Y242818D01*
G01X663682D02*
X666500Y240000D01*
G01D02*
X669318Y237182D01*
G01X683093Y536112D02*
X685981Y539000D01*
G01D02*
X688869Y541888D01*
G01X683093D02*
X685981Y539000D01*
G01D02*
X688869Y536112D01*
G01X733163Y237182D02*
X735981Y240000D01*
G01D02*
X738799Y242818D01*
G01X733163D02*
X735981Y240000D01*
G01D02*
X738799Y237182D01*
G01X731093Y536112D02*
X733981Y539000D01*
G01D02*
X736869Y541888D01*
G01X731093D02*
X733981Y539000D01*
G01D02*
X736869Y536112D01*
G01X777163Y237182D02*
X779981Y240000D01*
G01X777163Y242818D02*
X779981Y240000D01*
G01D02*
X782799Y242818D01*
G01X779981Y240000D02*
X782799Y237182D01*
G01X821163D02*
X823981Y240000D01*
G01D02*
X826799Y242818D01*
G01X821163D02*
X823981Y240000D01*
G01D02*
X826799Y237182D01*
G54D16*
X253819Y277204D03*
X268819D03*
X411299D03*
X426299D03*
X568780D03*
X583780D03*
G54D26*
G01X253819D02*
X258864Y282249D01*
G01X253819Y277204D02*
X258864Y272159D01*
G01X263774D02*
X268819Y277204D01*
G01D02*
X273864Y282249D01*
G01X263774D02*
X268819Y277204D01*
G01D02*
X273864Y272159D01*
G01X248774D02*
X253819Y277204D01*
G01X248774Y282249D02*
X253819Y277204D01*
G01X249835Y473220D02*
X253819Y477204D01*
G01D02*
X257803Y481188D01*
G01X249835D02*
X253819Y477204D01*
G01D02*
X257803Y473220D01*
G01X411299Y277204D02*
X416344Y282249D01*
G01X406254D02*
X411299Y277204D01*
G01D02*
X416344Y272159D01*
G01X421254D02*
X426299Y277204D01*
G01X406254Y272159D02*
X411299Y277204D01*
G01X421254Y282249D02*
X426299Y277204D01*
G01X407315Y473220D02*
X411299Y477204D01*
G01D02*
X415283Y481188D01*
G01X407315D02*
X411299Y477204D01*
G01D02*
X415283Y473220D01*
G01X426299Y277204D02*
X431344Y282249D01*
G01X426299Y277204D02*
X431344Y272159D01*
G01X568780Y277204D02*
X573825Y282249D01*
G01X563735D02*
X568780Y277204D01*
G01D02*
X573825Y272159D01*
G01X563735D02*
X568780Y277204D01*
G01X564796Y473220D02*
X568780Y477204D01*
G01D02*
X572764Y481188D01*
G01X564796D02*
X568780Y477204D01*
G01D02*
X572764Y473220D01*
G01X578735Y272159D02*
X583780Y277204D01*
G01D02*
X588825Y282249D01*
G01X578735D02*
X583780Y277204D01*
G01D02*
X588825Y272159D01*
G01X722277Y473220D02*
X726261Y477204D01*
G01D02*
X730245Y481188D01*
G01X722277D02*
X726261Y477204D01*
G01D02*
X730245Y473220D01*
G54D17*
X253819Y477204D03*
X411299D03*
X568780D03*
X726261D03*
G54D27*
G01X-297025Y-1013390D02*
Y1828909D01*
X3691357D01*
Y-1013390D01*
X-297025D01*
G01X4093Y-769672D02*
Y-844672D01*
X504093D01*
Y-769672D01*
X4093D01*
G01X16093Y-834672D02*
Y-839672D01*
G01X14636Y-834672D02*
X17550D01*
G01X22460Y-839672D02*
X19926D01*
Y-834672D01*
X22460D01*
G01X21446Y-837089D02*
X19926D01*
G01X25026Y-834672D02*
Y-839672D01*
X27560D01*
G01X31393Y-839839D02*
X31266Y-839755D01*
Y-839589D01*
X31393Y-839505D01*
X31520Y-839589D01*
Y-839755D01*
X31393Y-839839D01*
G01Y-837589D02*
X31266Y-837505D01*
Y-837339D01*
X31393Y-837255D01*
X31520Y-837339D01*
Y-837505D01*
X31393Y-837589D01*
G01X36176Y-841339D02*
X35543Y-840505D01*
X35226Y-839672D01*
Y-836339D01*
X35543Y-835505D01*
X36176Y-834672D01*
G01X41593D02*
X41086Y-834839D01*
X40706Y-835255D01*
X40453Y-835755D01*
X40263Y-836422D01*
X40200Y-837172D01*
X40263Y-837922D01*
X40453Y-838589D01*
X40706Y-839089D01*
X41086Y-839505D01*
X41593Y-839672D01*
X42100Y-839505D01*
X42480Y-839089D01*
X42733Y-838589D01*
X42923Y-837922D01*
X42986Y-837172D01*
X42923Y-836422D01*
X42733Y-835755D01*
X42480Y-835255D01*
X42100Y-834839D01*
X41593Y-834672D01*
G01X45300Y-838672D02*
X45680Y-839255D01*
X46186Y-839589D01*
X46756Y-839672D01*
X47263Y-839589D01*
X47770Y-839172D01*
X48086Y-838672D01*
X48150Y-838172D01*
X48023Y-837589D01*
X47580Y-837172D01*
X47136Y-837005D01*
X46566D01*
G01X47136D02*
X47516Y-836755D01*
X47833Y-836339D01*
X47960Y-835839D01*
X47833Y-835339D01*
X47516Y-834922D01*
X46946Y-834672D01*
X46376Y-834755D01*
X45806Y-835089D01*
G01X52110Y-841339D02*
X52743Y-840505D01*
X53060Y-839672D01*
Y-836339D01*
X52743Y-835505D01*
X52110Y-834672D01*
G01X55500Y-838672D02*
X55880Y-839255D01*
X56386Y-839589D01*
X56956Y-839672D01*
X57463Y-839589D01*
X57970Y-839172D01*
X58286Y-838672D01*
X58350Y-838172D01*
X58223Y-837589D01*
X57780Y-837172D01*
X57336Y-837005D01*
X56766D01*
G01X57336D02*
X57716Y-836755D01*
X58033Y-836339D01*
X58160Y-835839D01*
X58033Y-835339D01*
X57716Y-834922D01*
X57146Y-834672D01*
X56576Y-834755D01*
X56006Y-835089D01*
G01X60790Y-835505D02*
X61170Y-835005D01*
X61613Y-834755D01*
X62120Y-834672D01*
X62753Y-834839D01*
X63196Y-835255D01*
X63323Y-835755D01*
X63260Y-836255D01*
X63006Y-836672D01*
X61740Y-837505D01*
X61170Y-838089D01*
X60790Y-838922D01*
X60663Y-839672D01*
X63323D01*
G01X66966D02*
X67093Y-838589D01*
X67283Y-837672D01*
X67536Y-836839D01*
X67853Y-835922D01*
X68360Y-834672D01*
X65826D01*
G01X71370Y-838005D02*
X73016D01*
G01X76090Y-835505D02*
X76470Y-835005D01*
X76913Y-834755D01*
X77420Y-834672D01*
X78053Y-834839D01*
X78496Y-835255D01*
X78623Y-835755D01*
X78560Y-836255D01*
X78306Y-836672D01*
X77040Y-837505D01*
X76470Y-838089D01*
X76090Y-838922D01*
X75963Y-839672D01*
X78623D01*
G01X81000Y-838672D02*
X81380Y-839255D01*
X81886Y-839589D01*
X82456Y-839672D01*
X82963Y-839589D01*
X83470Y-839172D01*
X83786Y-838672D01*
X83850Y-838172D01*
X83723Y-837589D01*
X83280Y-837172D01*
X82836Y-837005D01*
X82266D01*
G01X82836D02*
X83216Y-836755D01*
X83533Y-836339D01*
X83660Y-835839D01*
X83533Y-835339D01*
X83216Y-834922D01*
X82646Y-834672D01*
X82076Y-834755D01*
X81506Y-835089D01*
G01X88253Y-839672D02*
Y-834672D01*
X85910Y-838255D01*
X89076D01*
G01X91200Y-838922D02*
X91580Y-839339D01*
X92023Y-839589D01*
X92593Y-839672D01*
X93163Y-839505D01*
X93606Y-839172D01*
X93923Y-838589D01*
X93986Y-837922D01*
X93860Y-837255D01*
X93543Y-836839D01*
X93100Y-836505D01*
X92656Y-836422D01*
X92213Y-836505D01*
X91643Y-836839D01*
X91833Y-834672D01*
X93543D01*
G01X101590Y-839672D02*
Y-834672D01*
X103996D01*
G01X103110Y-837089D02*
X101590D01*
G01X106310Y-839672D02*
X107893Y-834672D01*
X109476Y-839672D01*
G01X108906Y-837922D02*
X106880D01*
G01X111663Y-839672D02*
X114323Y-834672D01*
G01X111663D02*
X114323Y-839672D01*
G01X118093Y-839839D02*
X117966Y-839755D01*
Y-839589D01*
X118093Y-839505D01*
X118220Y-839589D01*
Y-839755D01*
X118093Y-839839D01*
G01Y-837589D02*
X117966Y-837505D01*
Y-837339D01*
X118093Y-837255D01*
X118220Y-837339D01*
Y-837505D01*
X118093Y-837589D01*
G01X122876Y-841339D02*
X122243Y-840505D01*
X121926Y-839672D01*
Y-836339D01*
X122243Y-835505D01*
X122876Y-834672D01*
G01X128293D02*
X127786Y-834839D01*
X127406Y-835255D01*
X127153Y-835755D01*
X126963Y-836422D01*
X126900Y-837172D01*
X126963Y-837922D01*
X127153Y-838589D01*
X127406Y-839089D01*
X127786Y-839505D01*
X128293Y-839672D01*
X128800Y-839505D01*
X129180Y-839089D01*
X129433Y-838589D01*
X129623Y-837922D01*
X129686Y-837172D01*
X129623Y-836422D01*
X129433Y-835755D01*
X129180Y-835255D01*
X128800Y-834839D01*
X128293Y-834672D01*
G01X132000Y-838672D02*
X132380Y-839255D01*
X132886Y-839589D01*
X133456Y-839672D01*
X133963Y-839589D01*
X134470Y-839172D01*
X134786Y-838672D01*
X134850Y-838172D01*
X134723Y-837589D01*
X134280Y-837172D01*
X133836Y-837005D01*
X133266D01*
G01X133836D02*
X134216Y-836755D01*
X134533Y-836339D01*
X134660Y-835839D01*
X134533Y-835339D01*
X134216Y-834922D01*
X133646Y-834672D01*
X133076Y-834755D01*
X132506Y-835089D01*
G01X138810Y-841339D02*
X139443Y-840505D01*
X139760Y-839672D01*
Y-836339D01*
X139443Y-835505D01*
X138810Y-834672D01*
G01X142200Y-838672D02*
X142580Y-839255D01*
X143086Y-839589D01*
X143656Y-839672D01*
X144163Y-839589D01*
X144670Y-839172D01*
X144986Y-838672D01*
X145050Y-838172D01*
X144923Y-837589D01*
X144480Y-837172D01*
X144036Y-837005D01*
X143466D01*
G01X144036D02*
X144416Y-836755D01*
X144733Y-836339D01*
X144860Y-835839D01*
X144733Y-835339D01*
X144416Y-834922D01*
X143846Y-834672D01*
X143276Y-834755D01*
X142706Y-835089D01*
G01X147616Y-839089D02*
X148060Y-839505D01*
X148566Y-839672D01*
X149073Y-839505D01*
X149516Y-839005D01*
X149833Y-838255D01*
X149960Y-837505D01*
Y-836589D01*
X149833Y-835839D01*
X149516Y-835172D01*
X149136Y-834839D01*
X148693Y-834672D01*
X148186Y-834839D01*
X147806Y-835172D01*
X147553Y-835672D01*
X147426Y-836339D01*
X147553Y-836922D01*
X147870Y-837505D01*
X148250Y-837839D01*
X148693Y-837922D01*
X149200Y-837755D01*
X149580Y-837339D01*
X149960Y-836589D01*
G01X153666Y-839672D02*
X153793Y-838589D01*
X153983Y-837672D01*
X154236Y-836839D01*
X154553Y-835922D01*
X155060Y-834672D01*
X152526D01*
G01X158070Y-838005D02*
X159716D01*
G01X162600Y-838672D02*
X162980Y-839255D01*
X163486Y-839589D01*
X164056Y-839672D01*
X164563Y-839589D01*
X165070Y-839172D01*
X165386Y-838672D01*
X165450Y-838172D01*
X165323Y-837589D01*
X164880Y-837172D01*
X164436Y-837005D01*
X163866D01*
G01X164436D02*
X164816Y-836755D01*
X165133Y-836339D01*
X165260Y-835839D01*
X165133Y-835339D01*
X164816Y-834922D01*
X164246Y-834672D01*
X163676Y-834755D01*
X163106Y-835089D01*
G01X167890Y-837589D02*
X168333Y-837005D01*
X168713Y-836672D01*
X169220Y-836505D01*
X169663Y-836672D01*
X169980Y-837005D01*
X170233Y-837505D01*
X170296Y-838089D01*
X170233Y-838589D01*
X169980Y-839089D01*
X169600Y-839505D01*
X169156Y-839672D01*
X168650Y-839505D01*
X168206Y-839005D01*
X167953Y-838255D01*
X167890Y-837422D01*
X168016Y-836339D01*
X168206Y-835755D01*
X168523Y-835172D01*
X168966Y-834755D01*
X169410Y-834672D01*
X169853Y-834839D01*
X170170Y-835255D01*
G01X174193Y-839672D02*
Y-834672D01*
X173433Y-835672D01*
G01Y-839672D02*
X174953D01*
G01X180053D02*
Y-834672D01*
X177710Y-838255D01*
X180876D01*
G01X199093Y-769672D02*
Y-844672D01*
G01Y-819672D02*
X302093D01*
Y-794672D01*
G01X199093D02*
X302093D01*
G01X309600Y-829672D02*
Y-824672D01*
X310866D01*
X311373Y-824922D01*
X311753Y-825255D01*
X312070Y-825755D01*
X312323Y-826339D01*
X312386Y-827172D01*
X312323Y-828005D01*
X312070Y-828589D01*
X311753Y-829089D01*
X311373Y-829422D01*
X310866Y-829672D01*
X309600D01*
G01X314510D02*
X316093Y-824672D01*
X317676Y-829672D01*
G01X317106Y-827922D02*
X315080D01*
G01X321193Y-824672D02*
Y-829672D01*
G01X319736Y-824672D02*
X322650D01*
G01X327560Y-829672D02*
X325026D01*
Y-824672D01*
X327560D01*
G01X326546Y-827089D02*
X325026D01*
G01X331393Y-829839D02*
X331266Y-829755D01*
Y-829589D01*
X331393Y-829505D01*
X331520Y-829589D01*
Y-829755D01*
X331393Y-829839D01*
G01Y-827589D02*
X331266Y-827505D01*
Y-827339D01*
X331393Y-827255D01*
X331520Y-827339D01*
Y-827505D01*
X331393Y-827589D01*
G01X304093Y-769672D02*
Y-844672D01*
G01X302093Y-769672D02*
Y-844672D01*
G01X304093Y-819672D02*
X504093D01*
G01X309726Y-804672D02*
Y-799672D01*
X311246D01*
X311753Y-799922D01*
X312133Y-800505D01*
X312260Y-801172D01*
X312133Y-801839D01*
X311816Y-802339D01*
X311246Y-802589D01*
X309726D01*
G01X314953Y-804839D02*
X317233Y-799672D01*
G01X319736Y-804672D02*
Y-799672D01*
X322650Y-804672D01*
Y-799672D01*
G01X326293Y-804839D02*
X326166Y-804755D01*
Y-804589D01*
X326293Y-804505D01*
X326420Y-804589D01*
Y-804755D01*
X326293Y-804839D01*
G01Y-802589D02*
X326166Y-802505D01*
Y-802339D01*
X326293Y-802255D01*
X326420Y-802339D01*
Y-802505D01*
X326293Y-802589D01*
G01X304093Y-794672D02*
X504093D01*
G01X309726Y-779672D02*
Y-774672D01*
X311246D01*
X311753Y-774922D01*
X312133Y-775505D01*
X312260Y-776172D01*
X312133Y-776839D01*
X311816Y-777339D01*
X311246Y-777589D01*
X309726D01*
G01X314826Y-779672D02*
Y-774672D01*
X316410D01*
X316916Y-774922D01*
X317233Y-775255D01*
X317360Y-775922D01*
X317233Y-776589D01*
X316853Y-777005D01*
X316410Y-777255D01*
X314826D01*
G01X316410D02*
X317360Y-779672D01*
G01X321193D02*
X320686Y-779589D01*
X320243Y-779255D01*
X319863Y-778755D01*
X319610Y-778172D01*
X319483Y-777505D01*
Y-776839D01*
X319610Y-776172D01*
X319863Y-775589D01*
X320243Y-775089D01*
X320686Y-774755D01*
X321193Y-774672D01*
X321700Y-774755D01*
X322143Y-775089D01*
X322523Y-775589D01*
X322776Y-776172D01*
X322903Y-776839D01*
Y-777505D01*
X322776Y-778172D01*
X322523Y-778755D01*
X322143Y-779255D01*
X321700Y-779589D01*
X321193Y-779672D01*
G01X325026Y-778672D02*
X325343Y-779172D01*
X325723Y-779505D01*
X326166Y-779672D01*
X326673Y-779505D01*
X327053Y-779172D01*
X327433Y-778672D01*
X327560Y-778005D01*
Y-774672D01*
G01X332660Y-779672D02*
X330126D01*
Y-774672D01*
X332660D01*
G01X331646Y-777089D02*
X330126D01*
G01X337886Y-775089D02*
X337506Y-774839D01*
X337063Y-774672D01*
X336556D01*
X335986Y-774922D01*
X335543Y-775339D01*
X335226Y-775839D01*
X334973Y-776672D01*
X334910Y-777422D01*
X335036Y-778172D01*
X335226Y-778672D01*
X335606Y-779172D01*
X336050Y-779505D01*
X336493Y-779672D01*
X336936D01*
X337380Y-779505D01*
X337760Y-779255D01*
X338076Y-778922D01*
G01X341593Y-774672D02*
Y-779672D01*
G01X340136Y-774672D02*
X343050D01*
G01X346693Y-779839D02*
X346566Y-779755D01*
Y-779589D01*
X346693Y-779505D01*
X346820Y-779589D01*
Y-779755D01*
X346693Y-779839D01*
G01Y-777589D02*
X346566Y-777505D01*
Y-777339D01*
X346693Y-777255D01*
X346820Y-777339D01*
Y-777505D01*
X346693Y-777589D01*
G01X419093Y-819672D02*
Y-844672D01*
G01X421726Y-822172D02*
Y-827172D01*
X424260D01*
G01X427333Y-822172D02*
X428853D01*
G01X428093D02*
Y-827172D01*
G01X427333D02*
X428853D01*
G01X433700Y-824505D02*
X433953Y-824255D01*
X434143Y-823839D01*
X434270Y-823255D01*
X434143Y-822755D01*
X433890Y-822422D01*
X433446Y-822172D01*
X431736D01*
Y-827172D01*
X433826D01*
X434270Y-826839D01*
X434523Y-826339D01*
X434650Y-825755D01*
X434523Y-825172D01*
X434143Y-824672D01*
X433700Y-824505D01*
X431736D01*
G01X438293Y-827339D02*
X438166Y-827255D01*
Y-827089D01*
X438293Y-827005D01*
X438420Y-827089D01*
Y-827255D01*
X438293Y-827339D01*
G01Y-825089D02*
X438166Y-825005D01*
Y-824839D01*
X438293Y-824755D01*
X438420Y-824839D01*
Y-825005D01*
X438293Y-825089D01*
G01X470106Y-847839D02*
X470213Y-847714D01*
X470293Y-847505D01*
X470346Y-847214D01*
X470293Y-846964D01*
X470186Y-846797D01*
X470000Y-846672D01*
X469280D01*
Y-849172D01*
X470160D01*
X470346Y-849005D01*
X470453Y-848755D01*
X470506Y-848464D01*
X470453Y-848172D01*
X470293Y-847922D01*
X470106Y-847839D01*
X469280D01*
G01X472573Y-849172D02*
Y-847505D01*
G01Y-847797D02*
X472466Y-847630D01*
X472306Y-847547D01*
X472120Y-847505D01*
X471933Y-847589D01*
X471773Y-847755D01*
X471666Y-848005D01*
X471613Y-848339D01*
X471666Y-848672D01*
X471773Y-848922D01*
X471933Y-849089D01*
X472120Y-849172D01*
X472306Y-849130D01*
X472466Y-849005D01*
X472573Y-848839D01*
G01X473893Y-848880D02*
X474026Y-849047D01*
X474213Y-849172D01*
X474373D01*
X474533Y-849089D01*
X474640Y-848964D01*
X474693Y-848797D01*
X474666Y-848547D01*
X474560Y-848422D01*
X474080Y-848172D01*
X473973Y-847880D01*
X474026Y-847672D01*
X474133Y-847547D01*
X474293Y-847505D01*
X474453Y-847547D01*
X474613Y-847672D01*
G01X476093Y-848047D02*
X476946D01*
X476866Y-847755D01*
X476733Y-847589D01*
X476546Y-847505D01*
X476360Y-847547D01*
X476200Y-847672D01*
X476093Y-847964D01*
X476040Y-848214D01*
Y-848464D01*
X476093Y-848714D01*
X476226Y-848964D01*
X476386Y-849130D01*
X476573Y-849172D01*
X476760Y-849089D01*
X476946Y-848839D01*
G01X478213Y-849172D02*
Y-846672D01*
G01Y-847922D02*
X478346Y-847672D01*
X478506Y-847547D01*
X478666Y-847505D01*
X478906Y-847589D01*
X479066Y-847755D01*
X479173Y-848047D01*
Y-848380D01*
X479120Y-848714D01*
X479013Y-848964D01*
X478826Y-849130D01*
X478666Y-849172D01*
X478506Y-849130D01*
X478346Y-849005D01*
X478213Y-848797D01*
G01X480893Y-849172D02*
X480733Y-849130D01*
X480573Y-848964D01*
X480466Y-848672D01*
X480413Y-848339D01*
X480466Y-848005D01*
X480573Y-847714D01*
X480733Y-847547D01*
X480893Y-847505D01*
X481053Y-847547D01*
X481213Y-847714D01*
X481320Y-848005D01*
X481346Y-848339D01*
X481320Y-848672D01*
X481213Y-848964D01*
X481053Y-849130D01*
X480893Y-849172D01*
G01X483573D02*
Y-847505D01*
G01Y-847797D02*
X483466Y-847630D01*
X483306Y-847547D01*
X483120Y-847505D01*
X482933Y-847589D01*
X482773Y-847755D01*
X482666Y-848005D01*
X482613Y-848339D01*
X482666Y-848672D01*
X482773Y-848922D01*
X482933Y-849089D01*
X483120Y-849172D01*
X483306Y-849130D01*
X483466Y-849005D01*
X483573Y-848839D01*
G01X484920Y-849172D02*
Y-847505D01*
G01Y-847839D02*
X485053Y-847672D01*
X485186Y-847547D01*
X485373Y-847505D01*
X485506Y-847547D01*
X485666Y-847672D01*
G01X487973Y-846672D02*
Y-849172D01*
G01Y-848797D02*
X487866Y-849005D01*
X487706Y-849130D01*
X487520Y-849172D01*
X487306Y-849089D01*
X487146Y-848880D01*
X487040Y-848630D01*
X487013Y-848339D01*
X487040Y-848047D01*
X487146Y-847797D01*
X487306Y-847589D01*
X487520Y-847505D01*
X487706Y-847547D01*
X487840Y-847630D01*
X487973Y-847797D01*
G01X491360Y-849172D02*
Y-846672D01*
X492026D01*
X492240Y-846797D01*
X492373Y-846964D01*
X492426Y-847297D01*
X492373Y-847630D01*
X492213Y-847839D01*
X492026Y-847964D01*
X491360D01*
G01X492026D02*
X492426Y-849172D01*
G01X493693Y-848047D02*
X494546D01*
X494466Y-847755D01*
X494333Y-847589D01*
X494146Y-847505D01*
X493960Y-847547D01*
X493800Y-847672D01*
X493693Y-847964D01*
X493640Y-848214D01*
Y-848464D01*
X493693Y-848714D01*
X493826Y-848964D01*
X493986Y-849130D01*
X494173Y-849172D01*
X494360Y-849089D01*
X494546Y-848839D01*
G01X495813Y-847505D02*
X496293Y-849172D01*
X496773Y-847505D01*
G01X498493Y-849255D02*
X498440Y-849214D01*
Y-849130D01*
X498493Y-849089D01*
X498546Y-849130D01*
Y-849214D01*
X498493Y-849255D01*
G01X500693Y-849172D02*
X500880Y-849130D01*
X501093Y-849005D01*
X501226Y-848797D01*
X501280Y-848505D01*
X501226Y-848214D01*
X501066Y-847964D01*
X500826Y-847839D01*
X500560D01*
X500400Y-847755D01*
X500266Y-847547D01*
X500213Y-847255D01*
X500293Y-846964D01*
X500480Y-846755D01*
X500693Y-846672D01*
X500906Y-846755D01*
X501093Y-846964D01*
X501173Y-847255D01*
X501120Y-847547D01*
X500986Y-847755D01*
X500826Y-847839D01*
X500560D01*
X500320Y-847964D01*
X500160Y-848214D01*
X500106Y-848505D01*
X500160Y-848797D01*
X500293Y-849005D01*
X500506Y-849130D01*
X500693Y-849172D01*
G01X503106Y-847839D02*
X503213Y-847714D01*
X503293Y-847505D01*
X503346Y-847214D01*
X503293Y-846964D01*
X503186Y-846797D01*
X503000Y-846672D01*
X502280D01*
Y-849172D01*
X503160D01*
X503346Y-849005D01*
X503453Y-848755D01*
X503506Y-848464D01*
X503453Y-848172D01*
X503293Y-847922D01*
X503106Y-847839D01*
X502280D01*
G01X465993Y-822172D02*
Y-827172D01*
G01X464536Y-822172D02*
X467450D01*
G01X471093Y-827172D02*
X470713Y-827089D01*
X470333Y-826755D01*
X470080Y-826172D01*
X469953Y-825505D01*
X470080Y-824839D01*
X470333Y-824255D01*
X470713Y-823922D01*
X471093Y-823839D01*
X471473Y-823922D01*
X471853Y-824255D01*
X472106Y-824839D01*
X472170Y-825505D01*
X472106Y-826172D01*
X471853Y-826755D01*
X471473Y-827089D01*
X471093Y-827172D01*
G01X476193D02*
X475813Y-827089D01*
X475433Y-826755D01*
X475180Y-826172D01*
X475053Y-825505D01*
X475180Y-824839D01*
X475433Y-824255D01*
X475813Y-823922D01*
X476193Y-823839D01*
X476573Y-823922D01*
X476953Y-824255D01*
X477206Y-824839D01*
X477270Y-825505D01*
X477206Y-826172D01*
X476953Y-826755D01*
X476573Y-827089D01*
X476193Y-827172D01*
G01X481293D02*
Y-822172D01*
G01X486393Y-827339D02*
X486266Y-827255D01*
Y-827089D01*
X486393Y-827005D01*
X486520Y-827089D01*
Y-827255D01*
X486393Y-827339D01*
G01Y-825089D02*
X486266Y-825005D01*
Y-824839D01*
X486393Y-824755D01*
X486520Y-824839D01*
Y-825005D01*
X486393Y-825089D01*
G01X462093Y-819672D02*
Y-844672D01*
G01Y-794672D02*
Y-819672D01*
G01X464726Y-802172D02*
Y-797172D01*
X466310D01*
X466816Y-797422D01*
X467133Y-797755D01*
X467260Y-798422D01*
X467133Y-799089D01*
X466753Y-799505D01*
X466310Y-799755D01*
X464726D01*
G01X466310D02*
X467260Y-802172D01*
G01X472360D02*
X469826D01*
Y-797172D01*
X472360D01*
G01X471346Y-799589D02*
X469826D01*
G01X474610Y-797172D02*
X476193Y-802172D01*
X477776Y-797172D01*
G01X481293Y-802339D02*
X481166Y-802255D01*
Y-802089D01*
X481293Y-802005D01*
X481420Y-802089D01*
Y-802255D01*
X481293Y-802339D01*
G01Y-800089D02*
X481166Y-800005D01*
Y-799839D01*
X481293Y-799755D01*
X481420Y-799839D01*
Y-800005D01*
X481293Y-800089D01*
G01X-297025Y-1013390D02*
Y1828909D01*
X3691357D01*
Y-1013390D01*
X-297025D01*
G01X16913Y-817022D02*
X18480D01*
Y-818912D01*
X18010Y-819542D01*
X17461Y-819962D01*
X16678Y-820172D01*
X15895Y-819962D01*
X15346Y-819542D01*
X14876Y-818912D01*
X14563Y-818177D01*
X14406Y-817337D01*
Y-816602D01*
X14563Y-815972D01*
X14876Y-815237D01*
X15346Y-814607D01*
X15816Y-814187D01*
X16443Y-813872D01*
X16991D01*
X17618Y-814082D01*
X18088Y-814502D01*
G01X21020Y-813872D02*
Y-818387D01*
X21333Y-819332D01*
X21960Y-819962D01*
X22743Y-820172D01*
X23526Y-819962D01*
X24153Y-819332D01*
X24466Y-818387D01*
Y-813872D01*
G01X28103D02*
X29983D01*
G01X29043D02*
Y-820172D01*
G01X28103D02*
X29983D01*
G01X33698Y-819332D02*
X34325Y-819857D01*
X35030Y-820172D01*
X35656D01*
X36283Y-819857D01*
X36753Y-819332D01*
X36988Y-818597D01*
X36831Y-817862D01*
X36440Y-817232D01*
X35735Y-816812D01*
X34795Y-816602D01*
X34246Y-816182D01*
X34011Y-815447D01*
X34168Y-814712D01*
X34560Y-814187D01*
X35108Y-813872D01*
X35656D01*
X36205Y-814082D01*
X36675Y-814607D01*
G01X39998Y-820172D02*
Y-813872D01*
G01X43288D02*
Y-820172D01*
G01Y-817022D02*
X39998D01*
G01X45985Y-820172D02*
X47943Y-813872D01*
X49901Y-820172D01*
G01X49196Y-817967D02*
X46690D01*
G01X52441Y-820172D02*
Y-813872D01*
X56045Y-820172D01*
Y-813872D01*
G01X65120Y-820172D02*
Y-813872D01*
X66686D01*
X67313Y-814187D01*
X67783Y-814607D01*
X68175Y-815237D01*
X68488Y-815972D01*
X68566Y-817022D01*
X68488Y-818072D01*
X68175Y-818807D01*
X67783Y-819437D01*
X67313Y-819857D01*
X66686Y-820172D01*
X65120D01*
G01X72203Y-813872D02*
X74083D01*
G01X73143D02*
Y-820172D01*
G01X72203D02*
X74083D01*
G01X77798Y-819332D02*
X78425Y-819857D01*
X79130Y-820172D01*
X79756D01*
X80383Y-819857D01*
X80853Y-819332D01*
X81088Y-818597D01*
X80931Y-817862D01*
X80540Y-817232D01*
X79835Y-816812D01*
X78895Y-816602D01*
X78346Y-816182D01*
X78111Y-815447D01*
X78268Y-814712D01*
X78660Y-814187D01*
X79208Y-813872D01*
X79756D01*
X80305Y-814082D01*
X80775Y-814607D01*
G01X85743Y-813872D02*
Y-820172D01*
G01X83941Y-813872D02*
X87545D01*
G01X92043Y-820382D02*
X91886Y-820277D01*
Y-820067D01*
X92043Y-819962D01*
X92200Y-820067D01*
Y-820277D01*
X92043Y-820382D01*
G01X98186Y-821327D02*
X98500Y-819962D01*
G01X104643Y-813872D02*
Y-820172D01*
G01X102841Y-813872D02*
X106445D01*
G01X108985Y-820172D02*
X110943Y-813872D01*
X112901Y-820172D01*
G01X112196Y-817967D02*
X109690D01*
G01X117243Y-820172D02*
X116616Y-820067D01*
X116068Y-819647D01*
X115598Y-819017D01*
X115285Y-818282D01*
X115128Y-817442D01*
Y-816602D01*
X115285Y-815762D01*
X115598Y-815027D01*
X116068Y-814397D01*
X116616Y-813977D01*
X117243Y-813872D01*
X117870Y-813977D01*
X118418Y-814397D01*
X118888Y-815027D01*
X119201Y-815762D01*
X119358Y-816602D01*
Y-817442D01*
X119201Y-818282D01*
X118888Y-819017D01*
X118418Y-819647D01*
X117870Y-820067D01*
X117243Y-820172D01*
G01X123543D02*
Y-817337D01*
X121976Y-813872D01*
G01X125110D02*
X123543Y-817337D01*
G01X128120Y-813872D02*
Y-818387D01*
X128433Y-819332D01*
X129060Y-819962D01*
X129843Y-820172D01*
X130626Y-819962D01*
X131253Y-819332D01*
X131566Y-818387D01*
Y-813872D01*
G01X134185Y-820172D02*
X136143Y-813872D01*
X138101Y-820172D01*
G01X137396Y-817967D02*
X134890D01*
G01X140641Y-820172D02*
Y-813872D01*
X144245Y-820172D01*
Y-813872D01*
G01X18166Y-824397D02*
X17696Y-824082D01*
X17148Y-823872D01*
X16521D01*
X15816Y-824187D01*
X15268Y-824712D01*
X14876Y-825342D01*
X14563Y-826392D01*
X14485Y-827337D01*
X14641Y-828282D01*
X14876Y-828912D01*
X15346Y-829542D01*
X15895Y-829962D01*
X16443Y-830172D01*
X16991D01*
X17540Y-829962D01*
X18010Y-829647D01*
X18401Y-829227D01*
G01X21803Y-823872D02*
X23683D01*
G01X22743D02*
Y-830172D01*
G01X21803D02*
X23683D01*
G01X29043Y-823872D02*
Y-830172D01*
G01X27241Y-823872D02*
X30845D01*
G01X35343Y-830172D02*
Y-827337D01*
X33776Y-823872D01*
G01X36910D02*
X35343Y-827337D01*
G01X46220Y-828912D02*
X46690Y-829647D01*
X47316Y-830067D01*
X48021Y-830172D01*
X48648Y-830067D01*
X49275Y-829542D01*
X49666Y-828912D01*
X49745Y-828282D01*
X49588Y-827547D01*
X49040Y-827022D01*
X48491Y-826812D01*
X47786D01*
G01X48491D02*
X48961Y-826497D01*
X49353Y-825972D01*
X49510Y-825342D01*
X49353Y-824712D01*
X48961Y-824187D01*
X48256Y-823872D01*
X47551Y-823977D01*
X46846Y-824397D01*
G01X52520Y-828912D02*
X52990Y-829647D01*
X53616Y-830067D01*
X54321Y-830172D01*
X54948Y-830067D01*
X55575Y-829542D01*
X55966Y-828912D01*
X56045Y-828282D01*
X55888Y-827547D01*
X55340Y-827022D01*
X54791Y-826812D01*
X54086D01*
G01X54791D02*
X55261Y-826497D01*
X55653Y-825972D01*
X55810Y-825342D01*
X55653Y-824712D01*
X55261Y-824187D01*
X54556Y-823872D01*
X53851Y-823977D01*
X53146Y-824397D01*
G01X58820Y-828912D02*
X59290Y-829647D01*
X59916Y-830067D01*
X60621Y-830172D01*
X61248Y-830067D01*
X61875Y-829542D01*
X62266Y-828912D01*
X62345Y-828282D01*
X62188Y-827547D01*
X61640Y-827022D01*
X61091Y-826812D01*
X60386D01*
G01X61091D02*
X61561Y-826497D01*
X61953Y-825972D01*
X62110Y-825342D01*
X61953Y-824712D01*
X61561Y-824187D01*
X60856Y-823872D01*
X60151Y-823977D01*
X59446Y-824397D01*
G01X66686Y-830172D02*
X66843Y-828807D01*
X67078Y-827652D01*
X67391Y-826602D01*
X67783Y-825447D01*
X68410Y-823872D01*
X65276D01*
G01X72986Y-830172D02*
X73143Y-828807D01*
X73378Y-827652D01*
X73691Y-826602D01*
X74083Y-825447D01*
X74710Y-823872D01*
X71576D01*
G01X79286Y-831327D02*
X79600Y-829962D01*
G01X85743Y-823872D02*
Y-830172D01*
G01X83941Y-823872D02*
X87545D01*
G01X90085Y-830172D02*
X92043Y-823872D01*
X94001Y-830172D01*
G01X93296Y-827967D02*
X90790D01*
G01X97403Y-823872D02*
X99283D01*
G01X98343D02*
Y-830172D01*
G01X97403D02*
X99283D01*
G01X102293Y-823872D02*
X103390Y-830172D01*
X104643Y-823872D01*
X105896Y-830172D01*
X106993Y-823872D01*
G01X108985Y-830172D02*
X110943Y-823872D01*
X112901Y-830172D01*
G01X112196Y-827967D02*
X109690D01*
G01X115441Y-830172D02*
Y-823872D01*
X119045Y-830172D01*
Y-823872D01*
G01X129451Y-832272D02*
X128668Y-831222D01*
X128276Y-830172D01*
Y-825972D01*
X128668Y-824922D01*
X129451Y-823872D01*
G01X140876Y-830172D02*
Y-823872D01*
X142835D01*
X143461Y-824187D01*
X143853Y-824607D01*
X144010Y-825447D01*
X143853Y-826287D01*
X143383Y-826812D01*
X142835Y-827127D01*
X140876D01*
G01X142835D02*
X144010Y-830172D01*
G01X148743Y-830382D02*
X148586Y-830277D01*
Y-830067D01*
X148743Y-829962D01*
X148900Y-830067D01*
Y-830277D01*
X148743Y-830382D01*
G01X155043Y-830172D02*
X154416Y-830067D01*
X153868Y-829647D01*
X153398Y-829017D01*
X153085Y-828282D01*
X152928Y-827442D01*
Y-826602D01*
X153085Y-825762D01*
X153398Y-825027D01*
X153868Y-824397D01*
X154416Y-823977D01*
X155043Y-823872D01*
X155670Y-823977D01*
X156218Y-824397D01*
X156688Y-825027D01*
X157001Y-825762D01*
X157158Y-826602D01*
Y-827442D01*
X157001Y-828282D01*
X156688Y-829017D01*
X156218Y-829647D01*
X155670Y-830067D01*
X155043Y-830172D01*
G01X161343Y-830382D02*
X161186Y-830277D01*
Y-830067D01*
X161343Y-829962D01*
X161500Y-830067D01*
Y-830277D01*
X161343Y-830382D01*
G01X169366Y-824397D02*
X168896Y-824082D01*
X168348Y-823872D01*
X167721D01*
X167016Y-824187D01*
X166468Y-824712D01*
X166076Y-825342D01*
X165763Y-826392D01*
X165685Y-827337D01*
X165841Y-828282D01*
X166076Y-828912D01*
X166546Y-829542D01*
X167095Y-829962D01*
X167643Y-830172D01*
X168191D01*
X168740Y-829962D01*
X169210Y-829647D01*
X169601Y-829227D01*
G01X173943Y-830382D02*
X173786Y-830277D01*
Y-830067D01*
X173943Y-829962D01*
X174100Y-830067D01*
Y-830277D01*
X173943Y-830382D01*
G01X180635Y-832272D02*
X181418Y-831222D01*
X181810Y-830172D01*
Y-825972D01*
X181418Y-824922D01*
X180635Y-823872D01*
G01X38743Y-799472D02*
X36223Y-799055D01*
X34018Y-797389D01*
X32128Y-794889D01*
X30868Y-791972D01*
X30238Y-788639D01*
Y-785305D01*
X30868Y-781972D01*
X32128Y-779055D01*
X34018Y-776556D01*
X36223Y-774889D01*
X38743Y-774472D01*
X41263Y-774889D01*
X43468Y-776556D01*
X45358Y-779055D01*
X46618Y-781972D01*
X47248Y-785305D01*
Y-788639D01*
X46618Y-791972D01*
X45358Y-794889D01*
X43468Y-797389D01*
X41263Y-799055D01*
X38743Y-799472D01*
G01X41263Y-792805D02*
X45043Y-799472D01*
G01X58588Y-782806D02*
Y-794472D01*
X59848Y-797389D01*
X61738Y-799055D01*
X63943Y-799472D01*
X66148Y-799055D01*
X68038Y-797389D01*
X69298Y-794472D01*
G01Y-799472D02*
Y-782806D01*
G01X94813Y-799472D02*
Y-782806D01*
G01Y-785722D02*
X93553Y-784056D01*
X91663Y-783222D01*
X89458Y-782806D01*
X87253Y-783639D01*
X85363Y-785305D01*
X84103Y-787806D01*
X83473Y-791139D01*
X84103Y-794472D01*
X85363Y-796973D01*
X87253Y-798639D01*
X89458Y-799472D01*
X91663Y-799055D01*
X93553Y-797806D01*
X94813Y-796139D01*
G01X108988Y-799472D02*
Y-782806D01*
G01Y-786972D02*
X110248Y-784889D01*
X112138Y-783222D01*
X114658Y-782806D01*
X116863Y-783222D01*
X118753Y-784889D01*
X119698Y-787806D01*
Y-799472D01*
G01X139543Y-774472D02*
Y-799472D01*
G01X135133Y-782806D02*
X143953D01*
G01X170413Y-799472D02*
Y-782806D01*
G01Y-785722D02*
X169153Y-784056D01*
X167263Y-783222D01*
X165058Y-782806D01*
X162853Y-783639D01*
X160963Y-785305D01*
X159703Y-787806D01*
X159073Y-791139D01*
X159703Y-794472D01*
X160963Y-796973D01*
X162853Y-798639D01*
X165058Y-799472D01*
X167263Y-799055D01*
X169153Y-797806D01*
X170413Y-796139D01*
G01X14641Y-810172D02*
Y-803872D01*
X18245Y-810172D01*
Y-803872D01*
G01X22743Y-810172D02*
X22116Y-810067D01*
X21568Y-809647D01*
X21098Y-809017D01*
X20785Y-808282D01*
X20628Y-807442D01*
Y-806602D01*
X20785Y-805762D01*
X21098Y-805027D01*
X21568Y-804397D01*
X22116Y-803977D01*
X22743Y-803872D01*
X23370Y-803977D01*
X23918Y-804397D01*
X24388Y-805027D01*
X24701Y-805762D01*
X24858Y-806602D01*
Y-807442D01*
X24701Y-808282D01*
X24388Y-809017D01*
X23918Y-809647D01*
X23370Y-810067D01*
X22743Y-810172D01*
G01X29043Y-810382D02*
X28886Y-810277D01*
Y-810067D01*
X29043Y-809962D01*
X29200Y-810067D01*
Y-810277D01*
X29043Y-810382D01*
G01X33855Y-804922D02*
X34325Y-804292D01*
X34873Y-803977D01*
X35500Y-803872D01*
X36283Y-804082D01*
X36831Y-804607D01*
X36988Y-805237D01*
X36910Y-805867D01*
X36596Y-806392D01*
X35030Y-807442D01*
X34325Y-808177D01*
X33855Y-809227D01*
X33698Y-810172D01*
X36988D01*
G01X41643D02*
Y-803872D01*
X40703Y-805132D01*
G01Y-810172D02*
X42583D01*
G01X47943D02*
Y-803872D01*
X47003Y-805132D01*
G01Y-810172D02*
X48883D01*
G01X54086Y-811327D02*
X54400Y-809962D01*
G01X58193Y-803872D02*
X59290Y-810172D01*
X60543Y-803872D01*
X61796Y-810172D01*
X62893Y-803872D01*
G01X68410Y-810172D02*
X65276D01*
Y-803872D01*
X68410D01*
G01X67156Y-806917D02*
X65276D01*
G01X71341Y-810172D02*
Y-803872D01*
X74945Y-810172D01*
Y-803872D01*
G01X77798Y-810172D02*
Y-803872D01*
G01X81088D02*
Y-810172D01*
G01Y-807022D02*
X77798D01*
G01X84020Y-803872D02*
Y-808387D01*
X84333Y-809332D01*
X84960Y-809962D01*
X85743Y-810172D01*
X86526Y-809962D01*
X87153Y-809332D01*
X87466Y-808387D01*
Y-803872D01*
G01X90085Y-810172D02*
X92043Y-803872D01*
X94001Y-810172D01*
G01X93296Y-807967D02*
X90790D01*
G01X103155Y-804922D02*
X103625Y-804292D01*
X104173Y-803977D01*
X104800Y-803872D01*
X105583Y-804082D01*
X106131Y-804607D01*
X106288Y-805237D01*
X106210Y-805867D01*
X105896Y-806392D01*
X104330Y-807442D01*
X103625Y-808177D01*
X103155Y-809227D01*
X102998Y-810172D01*
X106288D01*
G01X109141D02*
Y-803872D01*
X112745Y-810172D01*
Y-803872D01*
G01X115520Y-810172D02*
Y-803872D01*
X117086D01*
X117713Y-804187D01*
X118183Y-804607D01*
X118575Y-805237D01*
X118888Y-805972D01*
X118966Y-807022D01*
X118888Y-808072D01*
X118575Y-808807D01*
X118183Y-809437D01*
X117713Y-809857D01*
X117086Y-810172D01*
X115520D01*
G01X128276D02*
Y-803872D01*
X130235D01*
X130861Y-804187D01*
X131253Y-804607D01*
X131410Y-805447D01*
X131253Y-806287D01*
X130783Y-806812D01*
X130235Y-807127D01*
X128276D01*
G01X130235D02*
X131410Y-810172D01*
G01X134420D02*
Y-803872D01*
X135986D01*
X136613Y-804187D01*
X137083Y-804607D01*
X137475Y-805237D01*
X137788Y-805972D01*
X137866Y-807022D01*
X137788Y-808072D01*
X137475Y-808807D01*
X137083Y-809437D01*
X136613Y-809857D01*
X135986Y-810172D01*
X134420D01*
G01X142443Y-810382D02*
X142286Y-810277D01*
Y-810067D01*
X142443Y-809962D01*
X142600Y-810067D01*
Y-810277D01*
X142443Y-810382D01*
G01X210093Y-779172D02*
Y-787172D01*
X214093D01*
G01X221893D02*
Y-781839D01*
G01Y-782772D02*
X221493Y-782239D01*
X220893Y-781972D01*
X220193Y-781839D01*
X219493Y-782105D01*
X218893Y-782639D01*
X218493Y-783439D01*
X218293Y-784505D01*
X218493Y-785572D01*
X218893Y-786372D01*
X219493Y-786905D01*
X220193Y-787172D01*
X220893Y-787039D01*
X221493Y-786639D01*
X221893Y-786106D01*
G01X225993Y-789572D02*
X226593Y-789839D01*
X227393Y-789572D01*
X227893Y-789039D01*
X228293Y-788372D01*
X228893Y-786239D01*
X230193Y-781839D01*
G01X226993D02*
X228893Y-786239D01*
G01X234593Y-783572D02*
X237793D01*
X237493Y-782639D01*
X236993Y-782105D01*
X236293Y-781839D01*
X235593Y-781972D01*
X234993Y-782372D01*
X234593Y-783305D01*
X234393Y-784106D01*
Y-784905D01*
X234593Y-785705D01*
X235093Y-786505D01*
X235693Y-787039D01*
X236393Y-787172D01*
X237093Y-786905D01*
X237793Y-786106D01*
G01X242693Y-787172D02*
Y-781839D01*
G01Y-782905D02*
X243193Y-782372D01*
X243693Y-781972D01*
X244393Y-781839D01*
X244893Y-781972D01*
X245493Y-782372D01*
G01X229193Y-829172D02*
X232993D01*
X229193Y-837172D01*
X232993D01*
G01X239093Y-831839D02*
Y-837172D01*
G01Y-829705D02*
X238893Y-829572D01*
Y-829305D01*
X239093Y-829172D01*
X239293Y-829305D01*
Y-829572D01*
X239093Y-829705D01*
G01X245793Y-834505D02*
X248393D01*
G01X253093Y-837172D02*
Y-829172D01*
X255493D01*
X256293Y-829572D01*
X256893Y-830505D01*
X257093Y-831572D01*
X256893Y-832639D01*
X256393Y-833439D01*
X255493Y-833839D01*
X253093D01*
G01X263093Y-831839D02*
Y-837172D01*
G01Y-829705D02*
X262893Y-829572D01*
Y-829305D01*
X263093Y-829172D01*
X263293Y-829305D01*
Y-829572D01*
X263093Y-829705D01*
G01X269393Y-837172D02*
Y-831839D01*
G01Y-833172D02*
X269793Y-832505D01*
X270393Y-831972D01*
X271193Y-831839D01*
X271893Y-831972D01*
X272493Y-832505D01*
X272793Y-833439D01*
Y-837172D01*
G01X277693Y-839172D02*
X278393Y-839705D01*
X279193Y-839839D01*
X279893Y-839705D01*
X280493Y-839039D01*
X280893Y-838105D01*
Y-831839D01*
G01Y-832905D02*
X280493Y-832372D01*
X279893Y-831972D01*
X279193Y-831839D01*
X278393Y-832105D01*
X277893Y-832639D01*
X277493Y-833572D01*
X277293Y-834505D01*
X277393Y-835305D01*
X277793Y-836239D01*
X278393Y-836905D01*
X279193Y-837172D01*
X279793Y-837039D01*
X280493Y-836505D01*
X280893Y-835972D01*
G01X242393Y-804172D02*
X244793D01*
G01X243593D02*
Y-812172D01*
G01X242393D02*
X244793D01*
G01X249293D02*
Y-804172D01*
X253893Y-812172D01*
Y-804172D01*
G01X257693Y-805505D02*
X258293Y-804705D01*
X258993Y-804305D01*
X259793Y-804172D01*
X260793Y-804439D01*
X261493Y-805105D01*
X261693Y-805905D01*
X261593Y-806706D01*
X261193Y-807372D01*
X259193Y-808705D01*
X258293Y-809639D01*
X257693Y-810972D01*
X257493Y-812172D01*
X261693D01*
G01X263593Y-787172D02*
X264293Y-787039D01*
X265093Y-786639D01*
X265593Y-785972D01*
X265793Y-785039D01*
X265593Y-784106D01*
X264993Y-783305D01*
X264093Y-782905D01*
X263093D01*
X262493Y-782639D01*
X261993Y-781972D01*
X261793Y-781039D01*
X262093Y-780105D01*
X262793Y-779439D01*
X263593Y-779172D01*
X264393Y-779439D01*
X265093Y-780105D01*
X265393Y-781039D01*
X265193Y-781972D01*
X264693Y-782639D01*
X264093Y-782905D01*
X263093D01*
X262193Y-783305D01*
X261593Y-784106D01*
X261393Y-785039D01*
X261593Y-785972D01*
X262093Y-786639D01*
X262893Y-787039D01*
X263593Y-787172D01*
G01X336693Y-830505D02*
X337293Y-829705D01*
X337993Y-829305D01*
X338793Y-829172D01*
X339793Y-829439D01*
X340493Y-830105D01*
X340693Y-830905D01*
X340593Y-831706D01*
X340193Y-832372D01*
X338193Y-833705D01*
X337293Y-834639D01*
X336693Y-835972D01*
X336493Y-837172D01*
X340693D01*
G01X346593Y-829172D02*
X345793Y-829439D01*
X345193Y-830105D01*
X344793Y-830905D01*
X344493Y-831972D01*
X344393Y-833172D01*
X344493Y-834372D01*
X344793Y-835439D01*
X345193Y-836239D01*
X345793Y-836905D01*
X346593Y-837172D01*
X347393Y-836905D01*
X347993Y-836239D01*
X348393Y-835439D01*
X348693Y-834372D01*
X348793Y-833172D01*
X348693Y-831972D01*
X348393Y-830905D01*
X347993Y-830105D01*
X347393Y-829439D01*
X346593Y-829172D01*
G01X352693Y-830505D02*
X353293Y-829705D01*
X353993Y-829305D01*
X354793Y-829172D01*
X355793Y-829439D01*
X356493Y-830105D01*
X356693Y-830905D01*
X356593Y-831706D01*
X356193Y-832372D01*
X354193Y-833705D01*
X353293Y-834639D01*
X352693Y-835972D01*
X352493Y-837172D01*
X356693D01*
G01X360693Y-830505D02*
X361293Y-829705D01*
X361993Y-829305D01*
X362793Y-829172D01*
X363793Y-829439D01*
X364493Y-830105D01*
X364693Y-830905D01*
X364593Y-831706D01*
X364193Y-832372D01*
X362193Y-833705D01*
X361293Y-834639D01*
X360693Y-835972D01*
X360493Y-837172D01*
X364693D01*
G01X368793Y-837439D02*
X372393Y-829172D01*
G01X378593Y-837172D02*
Y-829172D01*
X377393Y-830772D01*
G01Y-837172D02*
X379793D01*
G01X384693Y-830505D02*
X385293Y-829705D01*
X385993Y-829305D01*
X386793Y-829172D01*
X387793Y-829439D01*
X388493Y-830105D01*
X388693Y-830905D01*
X388593Y-831706D01*
X388193Y-832372D01*
X386193Y-833705D01*
X385293Y-834639D01*
X384693Y-835972D01*
X384493Y-837172D01*
X388693D01*
G01X392793Y-837439D02*
X396393Y-829172D01*
G01X402593D02*
X401793Y-829439D01*
X401193Y-830105D01*
X400793Y-830905D01*
X400493Y-831972D01*
X400393Y-833172D01*
X400493Y-834372D01*
X400793Y-835439D01*
X401193Y-836239D01*
X401793Y-836905D01*
X402593Y-837172D01*
X403393Y-836905D01*
X403993Y-836239D01*
X404393Y-835439D01*
X404693Y-834372D01*
X404793Y-833172D01*
X404693Y-831972D01*
X404393Y-830905D01*
X403993Y-830105D01*
X403393Y-829439D01*
X402593Y-829172D01*
G01X408693Y-830505D02*
X409293Y-829705D01*
X409993Y-829305D01*
X410793Y-829172D01*
X411793Y-829439D01*
X412493Y-830105D01*
X412693Y-830905D01*
X412593Y-831706D01*
X412193Y-832372D01*
X410193Y-833705D01*
X409293Y-834639D01*
X408693Y-835972D01*
X408493Y-837172D01*
X412693D01*
G01X336393Y-814672D02*
Y-806672D01*
X338393D01*
X339193Y-807072D01*
X339793Y-807605D01*
X340293Y-808405D01*
X340693Y-809339D01*
X340793Y-810672D01*
X340693Y-812005D01*
X340293Y-812939D01*
X339793Y-813739D01*
X339193Y-814272D01*
X338393Y-814672D01*
X336393D01*
G01X344093D02*
X346593Y-806672D01*
X349093Y-814672D01*
G01X348193Y-811872D02*
X344993D01*
G01X354593Y-806672D02*
X353793Y-806939D01*
X353193Y-807605D01*
X352793Y-808405D01*
X352493Y-809472D01*
X352393Y-810672D01*
X352493Y-811872D01*
X352793Y-812939D01*
X353193Y-813739D01*
X353793Y-814405D01*
X354593Y-814672D01*
X355393Y-814405D01*
X355993Y-813739D01*
X356393Y-812939D01*
X356693Y-811872D01*
X356793Y-810672D01*
X356693Y-809472D01*
X356393Y-808405D01*
X355993Y-807605D01*
X355393Y-806939D01*
X354593Y-806672D01*
G01X360693Y-814672D02*
Y-806672D01*
X364493D01*
G01X363093Y-810539D02*
X360693D01*
G01X370593Y-806672D02*
X369793Y-806939D01*
X369193Y-807605D01*
X368793Y-808405D01*
X368493Y-809472D01*
X368393Y-810672D01*
X368493Y-811872D01*
X368793Y-812939D01*
X369193Y-813739D01*
X369793Y-814405D01*
X370593Y-814672D01*
X371393Y-814405D01*
X371993Y-813739D01*
X372393Y-812939D01*
X372693Y-811872D01*
X372793Y-810672D01*
X372693Y-809472D01*
X372393Y-808405D01*
X371993Y-807605D01*
X371393Y-806939D01*
X370593Y-806672D01*
G01X378593D02*
Y-814672D01*
G01X376293Y-806672D02*
X380893D01*
G01X384593Y-814672D02*
Y-806672D01*
X386993D01*
X387793Y-807072D01*
X388393Y-808005D01*
X388593Y-809072D01*
X388393Y-810139D01*
X387893Y-810939D01*
X386993Y-811339D01*
X384593D01*
G01X395393Y-810405D02*
X395793Y-810005D01*
X396093Y-809339D01*
X396293Y-808405D01*
X396093Y-807605D01*
X395693Y-807072D01*
X394993Y-806672D01*
X392293D01*
Y-814672D01*
X395593D01*
X396293Y-814139D01*
X396693Y-813339D01*
X396893Y-812405D01*
X396693Y-811472D01*
X396093Y-810672D01*
X395393Y-810405D01*
X392293D01*
G01X400093Y-814672D02*
X402593Y-806672D01*
X405093Y-814672D01*
G01X404193Y-811872D02*
X400993D01*
G01X408693Y-814672D02*
Y-806672D01*
X412493D01*
G01X411093Y-810539D02*
X408693D01*
G01X418593Y-806672D02*
X417793Y-806939D01*
X417193Y-807605D01*
X416793Y-808405D01*
X416493Y-809472D01*
X416393Y-810672D01*
X416493Y-811872D01*
X416793Y-812939D01*
X417193Y-813739D01*
X417793Y-814405D01*
X418593Y-814672D01*
X419393Y-814405D01*
X419993Y-813739D01*
X420393Y-812939D01*
X420693Y-811872D01*
X420793Y-810672D01*
X420693Y-809472D01*
X420393Y-808405D01*
X419993Y-807605D01*
X419393Y-806939D01*
X418593Y-806672D01*
G01X356693Y-787172D02*
Y-779172D01*
X360493D01*
G01X359093Y-783039D02*
X356693D01*
G01X366593Y-779172D02*
X365793Y-779439D01*
X365193Y-780105D01*
X364793Y-780905D01*
X364493Y-781972D01*
X364393Y-783172D01*
X364493Y-784372D01*
X364793Y-785439D01*
X365193Y-786239D01*
X365793Y-786905D01*
X366593Y-787172D01*
X367393Y-786905D01*
X367993Y-786239D01*
X368393Y-785439D01*
X368693Y-784372D01*
X368793Y-783172D01*
X368693Y-781972D01*
X368393Y-780905D01*
X367993Y-780105D01*
X367393Y-779439D01*
X366593Y-779172D01*
G01X374593D02*
Y-787172D01*
G01X372293Y-779172D02*
X376893D01*
G01X379593Y-789839D02*
X385593D01*
G01X388593Y-787172D02*
Y-779172D01*
X390993D01*
X391793Y-779572D01*
X392393Y-780505D01*
X392593Y-781572D01*
X392393Y-782639D01*
X391893Y-783439D01*
X390993Y-783839D01*
X388593D01*
G01X396393Y-787172D02*
Y-779172D01*
X398393D01*
X399193Y-779572D01*
X399793Y-780105D01*
X400293Y-780905D01*
X400693Y-781839D01*
X400793Y-783172D01*
X400693Y-784505D01*
X400293Y-785439D01*
X399793Y-786239D01*
X399193Y-786772D01*
X398393Y-787172D01*
X396393D01*
G01X407393Y-782905D02*
X407793Y-782505D01*
X408093Y-781839D01*
X408293Y-780905D01*
X408093Y-780105D01*
X407693Y-779572D01*
X406993Y-779172D01*
X404293D01*
Y-787172D01*
X407593D01*
X408293Y-786639D01*
X408693Y-785839D01*
X408893Y-784905D01*
X408693Y-783972D01*
X408093Y-783172D01*
X407393Y-782905D01*
X404293D01*
G01X411593Y-789839D02*
X417593D01*
G01X424793Y-779839D02*
X424193Y-779439D01*
X423493Y-779172D01*
X422693D01*
X421793Y-779572D01*
X421093Y-780239D01*
X420593Y-781039D01*
X420193Y-782372D01*
X420093Y-783572D01*
X420293Y-784772D01*
X420593Y-785572D01*
X421193Y-786372D01*
X421893Y-786905D01*
X422593Y-787172D01*
X423293D01*
X423993Y-786905D01*
X424593Y-786505D01*
X425093Y-785972D01*
G01X430593Y-787172D02*
X429793Y-787039D01*
X429093Y-786505D01*
X428493Y-785705D01*
X428093Y-784772D01*
X427893Y-783705D01*
Y-782639D01*
X428093Y-781572D01*
X428493Y-780639D01*
X429093Y-779839D01*
X429793Y-779305D01*
X430593Y-779172D01*
X431393Y-779305D01*
X432093Y-779839D01*
X432693Y-780639D01*
X433093Y-781572D01*
X433293Y-782639D01*
Y-783705D01*
X433093Y-784772D01*
X432693Y-785705D01*
X432093Y-786505D01*
X431393Y-787039D01*
X430593Y-787172D01*
G01X436293D02*
Y-779172D01*
X440893Y-787172D01*
Y-779172D01*
G01X444093D02*
X446593Y-787172D01*
X449093Y-779172D01*
G01X456593Y-787172D02*
X452593D01*
Y-779172D01*
X456593D01*
G01X454993Y-783039D02*
X452593D01*
G01X460593Y-787172D02*
Y-779172D01*
X463093D01*
X463893Y-779572D01*
X464393Y-780105D01*
X464593Y-781172D01*
X464393Y-782239D01*
X463793Y-782905D01*
X463093Y-783305D01*
X460593D01*
G01X463093D02*
X464593Y-787172D01*
G01X470593Y-779172D02*
Y-787172D01*
G01X468293Y-779172D02*
X472893D01*
G01X480593Y-787172D02*
X476593D01*
Y-779172D01*
X480593D01*
G01X478993Y-783039D02*
X476593D01*
G01X484593Y-787172D02*
Y-779172D01*
X487093D01*
X487893Y-779572D01*
X488393Y-780105D01*
X488593Y-781172D01*
X488393Y-782239D01*
X487793Y-782905D01*
X487093Y-783305D01*
X484593D01*
G01X487093D02*
X488593Y-787172D01*
G01X425093Y-840172D02*
Y-832172D01*
X423893Y-833772D01*
G01Y-840172D02*
X426293D01*
G01X431193Y-836839D02*
X431893Y-835905D01*
X432493Y-835372D01*
X433293Y-835105D01*
X433993Y-835372D01*
X434493Y-835905D01*
X434893Y-836705D01*
X434993Y-837639D01*
X434893Y-838439D01*
X434493Y-839239D01*
X433893Y-839905D01*
X433193Y-840172D01*
X432393Y-839905D01*
X431693Y-839106D01*
X431293Y-837905D01*
X431193Y-836572D01*
X431393Y-834839D01*
X431693Y-833905D01*
X432193Y-832972D01*
X432893Y-832305D01*
X433593Y-832172D01*
X434293Y-832439D01*
X434793Y-833105D01*
G01X441093Y-840439D02*
X440893Y-840305D01*
Y-840039D01*
X441093Y-839905D01*
X441293Y-840039D01*
Y-840305D01*
X441093Y-840439D01*
G01X447193Y-836839D02*
X447893Y-835905D01*
X448493Y-835372D01*
X449293Y-835105D01*
X449993Y-835372D01*
X450493Y-835905D01*
X450893Y-836705D01*
X450993Y-837639D01*
X450893Y-838439D01*
X450493Y-839239D01*
X449893Y-839905D01*
X449193Y-840172D01*
X448393Y-839905D01*
X447693Y-839106D01*
X447293Y-837905D01*
X447193Y-836572D01*
X447393Y-834839D01*
X447693Y-833905D01*
X448193Y-832972D01*
X448893Y-832305D01*
X449593Y-832172D01*
X450293Y-832439D01*
X450793Y-833105D01*
G01X470093Y-840172D02*
Y-832172D01*
X468893Y-833772D01*
G01Y-840172D02*
X471293D01*
G01X477893D02*
X478093Y-838439D01*
X478393Y-836972D01*
X478793Y-835639D01*
X479293Y-834172D01*
X480093Y-832172D01*
X476093D01*
G01X486093Y-840439D02*
X485893Y-840305D01*
Y-840039D01*
X486093Y-839905D01*
X486293Y-840039D01*
Y-840305D01*
X486093Y-840439D01*
G01X492193Y-833505D02*
X492793Y-832705D01*
X493493Y-832305D01*
X494293Y-832172D01*
X495293Y-832439D01*
X495993Y-833105D01*
X496193Y-833905D01*
X496093Y-834706D01*
X495693Y-835372D01*
X493693Y-836705D01*
X492793Y-837639D01*
X492193Y-838972D01*
X491993Y-840172D01*
X496193D01*
G01X490193Y-815172D02*
Y-807172D01*
X493993D01*
G01X492593Y-811039D02*
X490193D01*
G54D18*
X411752Y129685D03*
X401752D03*
X411752Y139685D03*
Y149685D03*
Y159685D03*
X401752Y139685D03*
Y149685D03*
Y159685D03*
X446752Y129685D03*
X436752D03*
X446752Y139685D03*
Y149685D03*
Y159685D03*
X436752Y139685D03*
Y149685D03*
Y159685D03*
X481752Y129685D03*
X471752D03*
X481752Y139685D03*
Y149685D03*
Y159685D03*
X471752Y139685D03*
Y149685D03*
Y159685D03*
X712559Y129408D03*
Y119408D03*
Y149408D03*
Y139408D03*
X722559Y129408D03*
Y119408D03*
X747559Y129408D03*
Y119408D03*
X722559Y149408D03*
Y139408D03*
X747559Y149408D03*
Y139408D03*
X757559Y129408D03*
Y119408D03*
Y149408D03*
Y139408D03*
X782559Y129408D03*
Y119408D03*
X792559Y129408D03*
Y119408D03*
X782559Y149408D03*
Y139408D03*
X792559Y149408D03*
Y139408D03*
X812559D03*
X852559Y129408D03*
Y119408D03*
X862559Y129408D03*
Y119408D03*
X852559Y149408D03*
Y139408D03*
X862559Y149408D03*
Y139408D03*
X887559Y129408D03*
Y119408D03*
Y149408D03*
Y139408D03*
X897559Y129408D03*
Y119408D03*
X922559Y129408D03*
Y119408D03*
X897559Y149408D03*
Y139408D03*
X922559Y149408D03*
Y139408D03*
X932559Y129408D03*
Y119408D03*
Y149408D03*
Y139408D03*
X1226024Y221929D03*
X1236024D03*
X1246024D03*
X1226024Y231929D03*
X1236024D03*
X1246024D03*
X1226024Y256929D03*
X1236024D03*
X1246024D03*
X1226024Y266929D03*
X1236024D03*
X1246024D03*
X1226024Y306929D03*
X1236024D03*
X1246024D03*
X1226024Y316929D03*
X1236024D03*
X1246024D03*
X1226024Y341929D03*
X1236024D03*
X1246024D03*
X1226024Y351929D03*
X1236024D03*
X1246024D03*
X1256024Y221929D03*
Y231929D03*
Y256929D03*
Y266929D03*
Y306929D03*
Y316929D03*
Y341929D03*
Y351929D03*
G54D28*
G01X63436Y353962D02*
X57500Y348026D01*
Y326919D01*
X49038Y319982D01*
X48780Y319724D01*
G01X203575Y297500D02*
X199075Y293000D01*
X163647D01*
X155055Y284408D01*
Y266644D01*
X172100Y249599D01*
Y236400D01*
X179300Y229200D01*
Y221430D01*
X183900Y216830D01*
G01X203575Y297500D02*
X205575Y299500D01*
X675975D01*
X676075Y299600D01*
G01X382963Y316400D02*
X213825D01*
X212925Y315500D01*
G01X221425Y313000D02*
X223000Y311425D01*
Y305000D01*
X226000Y302000D01*
X671501D01*
X672504Y303003D01*
X712503D01*
X715000Y305500D01*
Y308000D01*
X717500Y310500D01*
X722503D01*
X726453Y306550D01*
X766284D01*
X783064Y289770D01*
X823770D01*
X836500Y302500D01*
G01X230425Y313605D02*
X230570Y313750D01*
X382963D01*
G01X539619Y316400D02*
X382963D01*
G01Y313750D02*
X539269D01*
X539619Y313400D01*
G01X518575Y295500D02*
X678714D01*
X681500Y298286D01*
X768014D01*
X783300Y283000D01*
X807500D01*
X814000Y276500D01*
Y269000D01*
X820500Y262500D01*
X842000D01*
X843500Y261000D01*
Y258000D01*
X850750Y250750D01*
G01X680400Y310500D02*
X674500Y316400D01*
X539619D01*
G01Y313400D02*
X673600D01*
X678600Y308400D01*
X682600D01*
X687600Y313400D01*
X697100D01*
G01X867000Y291260D02*
X865900Y290160D01*
X829900D01*
X827140Y287400D01*
X782167D01*
X768971Y300596D01*
X677071D01*
X676075Y299600D01*
G01X735075Y326000D02*
X737000Y327925D01*
Y338000D01*
X734000Y341000D01*
X721700D01*
X697200Y316500D01*
X686400D01*
X680400Y310500D01*
G01X700040Y258960D02*
X700000Y259000D01*
Y289906D01*
X694406Y295500D01*
G01X735075Y336000D02*
X732385Y338690D01*
X722657D01*
X697367Y313400D01*
X697100D01*
G01X704400Y358600D02*
X713279Y349721D01*
X748947D01*
X774368Y324300D01*
X782000D01*
X783464Y325764D01*
X800001D01*
X805885Y319880D01*
X815120D01*
X818690Y316310D01*
X882923D01*
X885690Y313543D01*
Y299690D01*
X869060Y283060D01*
X866078D01*
X862475Y279457D01*
Y255360D01*
X868930Y248905D01*
Y209643D01*
X889709Y188864D01*
X977101D01*
X1010380Y155585D01*
Y144752D01*
X1040252Y114880D01*
X1076954D01*
X1089690Y127616D01*
Y131810D01*
X1079865Y141635D01*
Y151401D01*
X1051000Y180266D01*
Y193500D01*
X1052190Y194690D01*
X1073970D01*
X1076500Y192160D01*
Y184000D01*
X1079000Y181500D01*
X1090231D01*
X1094500Y185769D01*
X1105964D01*
X1115690Y176043D01*
Y144190D01*
X1113000Y141500D01*
Y138083D01*
X1115110Y135973D01*
X1126075D01*
G01X697900Y352500D02*
X704600Y345800D01*
X749601D01*
X780801Y314600D01*
X810000D01*
X814800Y309800D01*
X841500D01*
X850900Y300400D01*
X857400D01*
X861600Y304600D01*
G01X1039016Y183027D02*
X1039889Y183900D01*
X1044099D01*
X1077555Y150444D01*
Y124248D01*
X1070497Y117190D01*
X1041209D01*
X1012690Y145709D01*
Y156542D01*
X978058Y191174D01*
X890666D01*
X871240Y210600D01*
Y249862D01*
X864785Y256317D01*
Y278500D01*
X867035Y280750D01*
X889250D01*
X890500Y282000D01*
Y315267D01*
X879957Y325810D01*
X835500D01*
X834190Y324500D01*
X807799D01*
X801915Y330384D01*
X772116D01*
X746854Y355646D01*
X710854D01*
X707750Y358750D01*
G01X1022575Y115500D02*
X999260Y138815D01*
Y156671D01*
X975187Y180744D01*
X884295D01*
X858810Y206229D01*
Y252491D01*
X857855Y253446D01*
Y281622D01*
X863913Y287680D01*
X866780D01*
X868890Y289790D01*
Y292310D01*
X868000Y293200D01*
X845100D01*
X839700Y298600D01*
Y302200D01*
X836900Y305000D01*
X821300D01*
X810800Y294500D01*
X781899D01*
X757709Y318690D01*
X736043D01*
X730000Y324733D01*
Y334075D01*
X731925Y336000D01*
G01X1022575Y100925D02*
Y112233D01*
X1025100Y114758D01*
Y116600D01*
X1001570Y140130D01*
Y157628D01*
X976144Y183054D01*
X885252D01*
X861120Y207186D01*
Y253448D01*
X860165Y254403D01*
Y280414D01*
X865121Y285370D01*
X867970D01*
X871200Y288600D01*
Y293500D01*
X869190Y295510D01*
X846057D01*
X842100Y299467D01*
Y303300D01*
X838000Y307400D01*
X820253D01*
X809943Y297090D01*
X783010D01*
X759100Y321000D01*
X737000D01*
X732000Y326000D01*
G01X935516Y361075D02*
X925441Y351000D01*
X919501D01*
X909001Y340500D01*
X842501D01*
X833601Y331600D01*
X807800D01*
X805500Y333900D01*
Y337533D01*
X799233Y343800D01*
X788400D01*
X773200Y359000D01*
X752510D01*
X752000Y358490D01*
Y354010D01*
X752510Y353500D01*
X754000D01*
G01Y356957D02*
X754657Y356300D01*
X772101D01*
X786911Y341490D01*
X794211D01*
X808701Y327000D01*
X832500D01*
X843690Y338190D01*
X882310D01*
X916500Y304000D01*
X940575D01*
G01X766604Y640687D02*
X1061490D01*
X1062000Y640177D01*
Y631197D01*
X1061490Y630687D01*
X766604D01*
G01X779100Y326820D02*
X780354Y328074D01*
X800958D01*
X806842Y322190D01*
X835190D01*
X836500Y323500D01*
X879000D01*
X888000Y314500D01*
Y283475D01*
G01X798400Y323900D02*
X804730Y317570D01*
X814031D01*
X817801Y313800D01*
X844900D01*
X853000Y305700D01*
Y303500D01*
G01X781500Y362700D02*
X791904D01*
X801104Y353500D01*
X819500D01*
X823755Y349245D01*
X850245D01*
X864755Y363755D01*
X908312D01*
X910992Y361075D01*
G01X808425Y334000D02*
X832734D01*
X841734Y343000D01*
X853000D01*
X869000Y359000D01*
Y360500D01*
G01X808425Y344000D02*
X810280Y342145D01*
X837145D01*
X841935Y346935D01*
X852935D01*
X864500Y358500D01*
G01X1053830Y191670D02*
Y180703D01*
X1082175Y152358D01*
Y149324D01*
X1092000Y139499D01*
Y126659D01*
X1077911Y112570D01*
X1039295D01*
X1008070Y143795D01*
Y154628D01*
X977198Y185500D01*
X887000D01*
X863600Y208900D01*
G01X868000Y271500D02*
X873550Y265950D01*
Y211558D01*
X891624Y193484D01*
X979016D01*
X1015000Y157500D01*
Y148500D01*
X1020917Y142583D01*
X1028979D01*
X1031348Y144952D01*
Y151348D01*
X1039538Y159538D01*
Y179208D01*
G01X903500Y327975D02*
Y330700D01*
X921300Y348500D01*
X928336D01*
X933196Y353360D01*
G01X1092000Y159500D02*
Y157000D01*
X1097000Y152000D01*
Y124500D01*
X1076265Y103765D01*
X1028683D01*
X1023988Y99070D01*
X1021806D01*
X1020265Y100611D01*
Y113190D01*
X1022575Y115500D01*
G01X1094500Y143144D02*
Y125500D01*
X1075075Y106075D01*
X1027725D01*
X1022575Y100925D01*
G01X1039538Y179208D02*
X1036934Y181812D01*
Y191434D01*
X1042500Y197000D01*
X1076000D01*
X1084921Y188079D01*
X1110421D01*
X1118000Y180500D01*
Y141500D01*
X1115425Y138925D01*
G01X1062500Y191500D02*
X1077000Y177000D01*
X1085650D01*
X1092000Y170650D01*
Y159500D01*
G01X1094500Y143144D02*
Y145200D01*
X1084000Y155700D01*
X1082100D01*
X1058000Y179800D01*
Y191500D01*
G01X1161000Y90400D02*
X1145900Y105500D01*
X1093500D01*
X1088000Y100000D01*
X1087000D01*
G54D19*
X766604Y630687D03*
Y640687D03*
M02*
